FILE_TYPE = MACRO_DRAWING;
SET COLOR_WIRE YELLOW;
SET COLOR_PROP ORANGE;
SET COLOR_DOT WHITE;
SET COLOR_ARC YELLOW;
SET COLOR_BODY GREEN;
SET COLOR_NOTE PURPLE;
SET PROP_DISPLAY VALUE;
SET PAGE_NUMBER P469;
FORCEADD UNIVERSAL_GND..1
(-8450 3000);
FORCEPROP 3 LASTPIN (-8450 3050) SIG_NAME GND\g
J 0
(-8440 3060);
DISPLAY 0.659574 (-8440 3060);
PAINT MONO (-8440 3060);
DISPLAY INVISIBLE (-8440 3060);
FORCEPROP 2 LAST CDS_LIB pure_quanta_power
J 0
(-8450 3000);
DISPLAY INVISIBLE (-8450 3000);
FORCEPROP 1 LAST HDL_POWER GND
J 1
(-8425 2925);
DISPLAY 0.872340 (-8425 2925);
PAINT GREEN (-8425 2925);
DISPLAY INVISIBLE (-8425 2925);
FORCEPROP 1 LAST PATH I1
J 0
(-8375 3000);
DISPLAY 0.872340 (-8375 3000);
PAINT AQUA (-8375 3000);
DISPLAY INVISIBLE (-8375 3000);
FORCEADD UNIVERSAL_GND..1
(-7925 2750);
FORCEPROP 3 LASTPIN (-7925 2800) SIG_NAME GND\g
J 0
(-7915 2810);
DISPLAY 0.659574 (-7915 2810);
PAINT MONO (-7915 2810);
DISPLAY INVISIBLE (-7915 2810);
FORCEPROP 2 LAST CDS_LIB pure_quanta_power
J 0
(-7925 2750);
DISPLAY INVISIBLE (-7925 2750);
FORCEPROP 1 LAST HDL_POWER GND
J 1
(-7900 2675);
DISPLAY 0.872340 (-7900 2675);
PAINT GREEN (-7900 2675);
DISPLAY INVISIBLE (-7900 2675);
FORCEPROP 1 LAST PATH I10
J 0
(-7850 2750);
DISPLAY 0.872340 (-7850 2750);
PAINT AQUA (-7850 2750);
DISPLAY INVISIBLE (-7850 2750);
FORCEADD UNIVERSAL_GND..1
(-7450 2150);
FORCEPROP 3 LASTPIN (-7450 2200) SIG_NAME GND\g
J 0
(-7440 2210);
DISPLAY 0.659574 (-7440 2210);
PAINT MONO (-7440 2210);
DISPLAY INVISIBLE (-7440 2210);
FORCEPROP 2 LAST CDS_LIB pure_quanta_power
J 0
(-7450 2150);
DISPLAY INVISIBLE (-7450 2150);
FORCEPROP 1 LAST HDL_POWER GND
J 1
(-7425 2075);
DISPLAY 0.872340 (-7425 2075);
PAINT GREEN (-7425 2075);
DISPLAY INVISIBLE (-7425 2075);
FORCEPROP 1 LAST PATH I11
J 0
(-7375 2150);
DISPLAY 0.872340 (-7375 2150);
PAINT AQUA (-7375 2150);
DISPLAY INVISIBLE (-7375 2150);
FORCEADD Q_CAP..1
R 2
(-7450 2375);
FORCEPROP 1 LAST LOCATION PC6506
J 0
(-7400 2515);
DISPLAY 0.489362 (-7400 2515);
PAINT SKYBLUE (-7400 2515);
FORCEPROP 2 LAST SEC 1
J 0
(-7500 2571);
DISPLAY 0.680851 (-7500 2571);
PAINT MONO (-7500 2571);
DISPLAY INVISIBLE (-7500 2571);
FORCEPROP 1 LASTPIN (-7450 2475) $PN 1
J 2
(-7404 2446);
DISPLAY 0.489362 (-7404 2446);
FORCEPROP 1 LASTPIN (-7450 2275) $PN 2
J 2
(-7406 2270);
DISPLAY 0.489362 (-7406 2270);
FORCEPROP 1 LAST TOLERANCE 10%
J 0
(-7400 2355);
DISPLAY 0.489362 (-7400 2355);
PAINT SKYBLUE (-7400 2355);
FORCEPROP 1 LAST VALUE 1UF
J 0
(-7400 2453);
DISPLAY 0.489362 (-7400 2453);
PAINT SKYBLUE (-7400 2453);
FORCEPROP 1 LAST VOLTAGE 25V
J 0
(-7400 2404);
DISPLAY 0.489362 (-7400 2404);
PAINT SKYBLUE (-7400 2404);
FORCEPROP 1 LAST MATERIAL X6S
J 0
(-7400 2306);
DISPLAY 0.489362 (-7400 2306);
PAINT SKYBLUE (-7400 2306);
FORCEPROP 1 LAST PACK_TYPE C0402
J 0
(-7400 2257);
DISPLAY 0.489362 (-7400 2257);
PAINT SKYBLUE (-7400 2257);
FORCEPROP 2 LAST SEC_TYPE C0402
J 0
(-7500 2571);
DISPLAY 1.021277 (-7500 2571);
DISPLAY INVISIBLE (-7500 2571);
FORCEPROP 2 LAST SIGNAL_MODEL DEFAULT_CAPACITOR_100000PF_2_1
R 3
J 1
(-7520 2323);
DISPLAY 0.744681 (-7520 2323);
PAINT MONO (-7520 2323);
DISPLAY INVISIBLE (-7520 2323);
FORCEPROP 2 LAST CDS_LIB pure_quanta
J 0
(-7450 2375);
DISPLAY INVISIBLE (-7450 2375);
FORCEPROP 1 LAST PATH I12
J 2
(-7500 2525);
DISPLAY 0.978723 (-7500 2525);
PAINT WHITE (-7500 2525);
DISPLAY INVISIBLE (-7500 2525);
FORCEPROP 1 LAST PART_NUMBER CH5104KEB02
J 0
(-7400 2208);
DISPLAY 0.489362 (-7400 2208);
PAINT SKYBLUE (-7400 2208);
DISPLAY INVISIBLE (-7400 2208);
FORCEADD Q_RES..2
(-7450 2800);
FORCEPROP 1 LAST LOCATION PR6501
J 0
(-7405 2925);
DISPLAY 0.489362 (-7405 2925);
PAINT SKYBLUE (-7405 2925);
FORCEPROP 0 LAST $SEC 1
J 0
(-7400 2975);
DISPLAY 0.680851 (-7400 2975);
PAINT MONO (-7400 2975);
DISPLAY INVISIBLE (-7400 2975);
FORCEPROP 0 LAST CDS_SEC 1
J 0
(-7400 2975);
DISPLAY 1.021277 (-7400 2975);
DISPLAY INVISIBLE (-7400 2975);
FORCEPROP 1 LASTPIN (-7450 2900) $PN 1
J 0
(-7445 2862);
DISPLAY 0.489362 (-7445 2862);
PAINT MONO (-7445 2862);
FORCEPROP 1 LASTPIN (-7450 2700) $PN 2
J 0
(-7445 2710);
DISPLAY 0.489362 (-7445 2710);
PAINT MONO (-7445 2710);
FORCEPROP 1 LAST PACK_TYPE 0402LF
J 0
(-7410 2625);
DISPLAY 0.489362 (-7410 2625);
PAINT SKYBLUE (-7410 2625);
FORCEPROP 1 LAST MATERIAL CHIP
J 0
(-7410 2725);
DISPLAY 0.489362 (-7410 2725);
PAINT SKYBLUE (-7410 2725);
FORCEPROP 1 LAST WATTAGE 1/16W
J 0
(-7410 2775);
DISPLAY 0.489362 (-7410 2775);
PAINT SKYBLUE (-7410 2775);
FORCEPROP 1 LAST TOLERANCE 5%
J 0
(-7405 2825);
DISPLAY 0.489362 (-7405 2825);
PAINT SKYBLUE (-7405 2825);
FORCEPROP 1 LAST VALUE 0
J 0
(-7405 2875);
DISPLAY 0.489362 (-7405 2875);
PAINT SKYBLUE (-7405 2875);
FORCEPROP 2 LAST CDS_LIB pure_quanta
J 0
(-7450 2800);
DISPLAY INVISIBLE (-7450 2800);
FORCEPROP 1 LAST PATH I13
J 0
(-7400 2975);
DISPLAY 0.978723 (-7400 2975);
PAINT WHITE (-7400 2975);
DISPLAY INVISIBLE (-7400 2975);
FORCEPROP 1 LAST PART_NUMBER CS00002JB13
J 0
(-7410 2675);
DISPLAY 0.489362 (-7410 2675);
PAINT SKYBLUE (-7410 2675);
DISPLAY INVISIBLE (-7410 2675);
FORCEADD UNIVERSAL_POWER..1
(-7450 3000);
FORCEPROP 3 LASTPIN (-7450 2950) SIG_NAME P3V3_AUX\g
J 0
(-7440 2960);
DISPLAY 0.659574 (-7440 2960);
PAINT MONO (-7440 2960);
DISPLAY INVISIBLE (-7440 2960);
FORCEPROP 1 LAST HDL_POWER P3V3_AUX
J 1
(-7450 3050);
DISPLAY 0.489362 (-7450 3050);
PAINT GREEN (-7450 3050);
FORCEPROP 2 LAST CDS_LIB mstr_symbols
J 0
(-7450 3000);
PAINT MONO (-7450 3000);
DISPLAY INVISIBLE (-7450 3000);
FORCEPROP 1 LAST PATH I14
J 0
(-7400 3025);
DISPLAY 0.872340 (-7400 3025);
PAINT AQUA (-7400 3025);
DISPLAY INVISIBLE (-7400 3025);
FORCEADD UNIVERSAL_GND..1
(-7475 3625);
FORCEPROP 3 LASTPIN (-7475 3675) SIG_NAME GND\g
J 0
(-7465 3685);
DISPLAY 0.659574 (-7465 3685);
PAINT MONO (-7465 3685);
DISPLAY INVISIBLE (-7465 3685);
FORCEPROP 2 LAST CDS_LIB pure_quanta_power
J 0
(-7475 3625);
DISPLAY INVISIBLE (-7475 3625);
FORCEPROP 1 LAST HDL_POWER GND
J 1
(-7450 3550);
DISPLAY 0.872340 (-7450 3550);
PAINT GREEN (-7450 3550);
DISPLAY INVISIBLE (-7450 3550);
FORCEPROP 1 LAST PATH I15
J 0
(-7400 3625);
DISPLAY 0.872340 (-7400 3625);
PAINT AQUA (-7400 3625);
DISPLAY INVISIBLE (-7400 3625);
FORCEADD Q_CAP..1
(-7975 3975);
FORCEPROP 1 LAST LOCATION PC6501
J 0
(-7925 4075);
DISPLAY 0.489362 (-7925 4075);
PAINT SKYBLUE (-7925 4075);
FORCEPROP 0 LAST $SEC 1
J 0
(-7925 4100);
DISPLAY 0.680851 (-7925 4100);
PAINT MONO (-7925 4100);
DISPLAY INVISIBLE (-7925 4100);
FORCEPROP 0 LAST CDS_SEC 1
J 0
(-7925 4100);
DISPLAY 1.021277 (-7925 4100);
DISPLAY INVISIBLE (-7925 4100);
FORCEPROP 1 LASTPIN (-7975 4075) $PN 1
J 0
(-7965 4055);
DISPLAY 0.489362 (-7965 4055);
PAINT MONO (-7965 4055);
FORCEPROP 1 LASTPIN (-7975 3875) $PN 2
J 0
(-7965 3855);
DISPLAY 0.489362 (-7965 3855);
PAINT MONO (-7965 3855);
FORCEPROP 1 LAST VOLTAGE 16V
J 0
(-7925 3975);
DISPLAY 0.489362 (-7925 3975);
PAINT SKYBLUE (-7925 3975);
FORCEPROP 1 LAST PACK_TYPE C0805
J 0
(-7925 3775);
DISPLAY 0.489362 (-7925 3775);
PAINT SKYBLUE (-7925 3775);
FORCEPROP 1 LAST VALUE 22UF
J 0
(-7925 4025);
DISPLAY 0.489362 (-7925 4025);
PAINT SKYBLUE (-7925 4025);
FORCEPROP 1 LAST TOLERANCE 20%
J 0
(-7925 3925);
DISPLAY 0.489362 (-7925 3925);
PAINT SKYBLUE (-7925 3925);
FORCEPROP 1 LAST MATERIAL X6S
J 0
(-7925 3875);
DISPLAY 0.489362 (-7925 3875);
PAINT SKYBLUE (-7925 3875);
FORCEPROP 2 LAST CDS_LIB pure_quanta
J 0
(-7975 3975);
DISPLAY INVISIBLE (-7975 3975);
FORCEPROP 1 LAST PATH I16
J 0
(-7925 4125);
DISPLAY 0.978723 (-7925 4125);
PAINT WHITE (-7925 4125);
DISPLAY INVISIBLE (-7925 4125);
FORCEPROP 1 LAST PART_NUMBER CH6223MEA01
J 0
(-7925 3825);
DISPLAY 0.489362 (-7925 3825);
PAINT SKYBLUE (-7925 3825);
DISPLAY INVISIBLE (-7925 3825);
FORCEADD Q_CAP..1
(-7750 3975);
FORCEPROP 1 LAST LOCATION PC6502
J 0
(-7700 4075);
DISPLAY 0.489362 (-7700 4075);
PAINT SKYBLUE (-7700 4075);
FORCEPROP 0 LAST $SEC 1
J 0
(-7700 4100);
DISPLAY 0.680851 (-7700 4100);
PAINT MONO (-7700 4100);
DISPLAY INVISIBLE (-7700 4100);
FORCEPROP 0 LAST CDS_SEC 1
J 0
(-7700 4125);
DISPLAY 1.021277 (-7700 4125);
DISPLAY INVISIBLE (-7700 4125);
FORCEPROP 1 LASTPIN (-7750 4075) $PN 1
J 0
(-7740 4055);
DISPLAY 0.489362 (-7740 4055);
PAINT MONO (-7740 4055);
FORCEPROP 1 LASTPIN (-7750 3875) $PN 2
J 0
(-7740 3855);
DISPLAY 0.489362 (-7740 3855);
PAINT MONO (-7740 3855);
FORCEPROP 1 LAST MATERIAL X6S
J 0
(-7700 3875);
DISPLAY 0.489362 (-7700 3875);
PAINT SKYBLUE (-7700 3875);
FORCEPROP 1 LAST VOLTAGE 16V
J 0
(-7700 3975);
DISPLAY 0.489362 (-7700 3975);
PAINT SKYBLUE (-7700 3975);
FORCEPROP 1 LAST VALUE 22UF
J 0
(-7700 4025);
DISPLAY 0.489362 (-7700 4025);
PAINT SKYBLUE (-7700 4025);
FORCEPROP 1 LAST TOLERANCE 20%
J 0
(-7700 3925);
DISPLAY 0.489362 (-7700 3925);
PAINT SKYBLUE (-7700 3925);
FORCEPROP 1 LAST PACK_TYPE C0805
J 0
(-7700 3775);
DISPLAY 0.489362 (-7700 3775);
PAINT SKYBLUE (-7700 3775);
FORCEPROP 2 LAST CDS_LIB pure_quanta
J 0
(-7750 3975);
DISPLAY INVISIBLE (-7750 3975);
FORCEPROP 1 LAST PATH I17
J 0
(-7700 4125);
DISPLAY 0.978723 (-7700 4125);
PAINT WHITE (-7700 4125);
DISPLAY INVISIBLE (-7700 4125);
FORCEPROP 1 LAST PART_NUMBER CH6223MEA01
J 0
(-7700 3825);
DISPLAY 0.489362 (-7700 3825);
PAINT SKYBLUE (-7700 3825);
DISPLAY INVISIBLE (-7700 3825);
FORCEADD Q_CAP..1
(-7550 3975);
FORCEPROP 1 LAST LOCATION PC6503
J 0
(-7500 4075);
DISPLAY 0.489362 (-7500 4075);
PAINT SKYBLUE (-7500 4075);
FORCEPROP 0 LAST $SEC 1
J 0
(-7500 4100);
DISPLAY 0.680851 (-7500 4100);
PAINT MONO (-7500 4100);
DISPLAY INVISIBLE (-7500 4100);
FORCEPROP 0 LAST CDS_SEC 1
J 0
(-7500 4125);
DISPLAY 1.021277 (-7500 4125);
DISPLAY INVISIBLE (-7500 4125);
FORCEPROP 1 LASTPIN (-7550 4075) $PN 1
J 0
(-7540 4055);
DISPLAY 0.489362 (-7540 4055);
PAINT MONO (-7540 4055);
FORCEPROP 1 LASTPIN (-7550 3875) $PN 2
J 0
(-7540 3855);
DISPLAY 0.489362 (-7540 3855);
PAINT MONO (-7540 3855);
FORCEPROP 1 LAST PACK_TYPE C0805
J 0
(-7500 3775);
DISPLAY 0.489362 (-7500 3775);
PAINT SKYBLUE (-7500 3775);
FORCEPROP 1 LAST TOLERANCE 20%
J 0
(-7500 3925);
DISPLAY 0.489362 (-7500 3925);
PAINT SKYBLUE (-7500 3925);
FORCEPROP 1 LAST MATERIAL X6S
J 0
(-7500 3875);
DISPLAY 0.489362 (-7500 3875);
PAINT SKYBLUE (-7500 3875);
FORCEPROP 1 LAST VOLTAGE 16V
J 0
(-7500 3975);
DISPLAY 0.489362 (-7500 3975);
PAINT SKYBLUE (-7500 3975);
FORCEPROP 1 LAST VALUE 22UF
J 0
(-7500 4025);
DISPLAY 0.489362 (-7500 4025);
PAINT SKYBLUE (-7500 4025);
FORCEPROP 2 LAST CDS_LIB pure_quanta
J 0
(-7550 3975);
DISPLAY INVISIBLE (-7550 3975);
FORCEPROP 1 LAST PATH I18
J 0
(-7500 4125);
DISPLAY 0.978723 (-7500 4125);
PAINT WHITE (-7500 4125);
DISPLAY INVISIBLE (-7500 4125);
FORCEPROP 1 LAST PART_NUMBER CH6223MEA01
J 0
(-7500 3825);
DISPLAY 0.489362 (-7500 3825);
PAINT SKYBLUE (-7500 3825);
DISPLAY INVISIBLE (-7500 3825);
FORCEADD UNIVERSAL_GND..1
(-6575 2125);
FORCEPROP 3 LASTPIN (-6575 2175) SIG_NAME GND\g
J 0
(-6565 2185);
DISPLAY 0.659574 (-6565 2185);
PAINT MONO (-6565 2185);
DISPLAY INVISIBLE (-6565 2185);
FORCEPROP 2 LAST CDS_LIB pure_quanta_power
J 0
(-6575 2125);
DISPLAY INVISIBLE (-6575 2125);
FORCEPROP 1 LAST HDL_POWER GND
J 1
(-6550 2050);
DISPLAY 0.872340 (-6550 2050);
PAINT GREEN (-6550 2050);
DISPLAY INVISIBLE (-6550 2050);
FORCEPROP 1 LAST PATH I19
J 0
(-6500 2125);
DISPLAY 0.872340 (-6500 2125);
PAINT AQUA (-6500 2125);
DISPLAY INVISIBLE (-6500 2125);
FORCEADD OFFPAGE..1
(-8725 3400);
FORCEPROP 2 LAST $XR0 80 
J 0
(-8976 3400);
DISPLAY 0.638298 (-8976 3400);
PAINT MONO (-8976 3400);
FORCEPROP 2 LAST CDS_LIB standard
J 0
(-8725 3400);
DISPLAY INVISIBLE (-8725 3400);
FORCEPROP 1 LAST OFFPAGE TRUE
J 0
(-8400 3275);
DISPLAY 0.872340 (-8400 3275);
PAINT GREEN (-8400 3275);
DISPLAY INVISIBLE (-8400 3275);
FORCEPROP 1 LAST COMMENT_BODY TRUE
J 0
(-8600 3300);
DISPLAY 0.872340 (-8600 3300);
PAINT GREEN (-8600 3300);
DISPLAY INVISIBLE (-8600 3300);
FORCEPROP 2 LAST PATH I2
J 0
(-8675 3475);
DISPLAY 0.680851 (-8675 3475);
DISPLAY INVISIBLE (-8675 3475);
FORCEADD Q_RES..2
(-6575 2375);
FORCEPROP 1 LAST LOCATION PR6502
J 0
(-6530 2500);
DISPLAY 0.489362 (-6530 2500);
PAINT SKYBLUE (-6530 2500);
FORCEPROP 2 LAST SEC 1
J 0
(-6513 2618);
DISPLAY 0.680851 (-6513 2618);
PAINT MONO (-6513 2618);
DISPLAY INVISIBLE (-6513 2618);
FORCEPROP 1 LASTPIN (-6575 2475) $PN 1
J 0
(-6570 2437);
DISPLAY 0.489362 (-6570 2437);
FORCEPROP 1 LASTPIN (-6575 2275) $PN 2
J 0
(-6570 2285);
DISPLAY 0.489362 (-6570 2285);
FORCEPROP 1 LAST MATERIAL CHIP
J 0
(-6535 2300);
DISPLAY 0.489362 (-6535 2300);
PAINT SKYBLUE (-6535 2300);
FORCEPROP 1 LAST TOLERANCE 1%
J 0
(-6530 2400);
DISPLAY 0.489362 (-6530 2400);
PAINT SKYBLUE (-6530 2400);
FORCEPROP 1 LAST WATTAGE 1/16W
J 0
(-6535 2350);
DISPLAY 0.489362 (-6535 2350);
PAINT SKYBLUE (-6535 2350);
FORCEPROP 1 LAST PACK_TYPE 0402LF
J 0
(-6535 2200);
DISPLAY 0.489362 (-6535 2200);
PAINT SKYBLUE (-6535 2200);
FORCEPROP 1 LAST VALUE 7.15K
J 0
(-6530 2450);
DISPLAY 0.489362 (-6530 2450);
PAINT SKYBLUE (-6530 2450);
FORCEPROP 2 LAST CDS_LIB pure_quanta
R 3
J 0
(-6575 2375);
DISPLAY INVISIBLE (-6575 2375);
FORCEPROP 2 LAST SEC_TYPE 0402LF
J 0
(-6513 2618);
DISPLAY 1.021277 (-6513 2618);
DISPLAY INVISIBLE (-6513 2618);
FORCEPROP 1 LAST PATH I20
J 0
(-6525 2550);
DISPLAY 0.978723 (-6525 2550);
PAINT WHITE (-6525 2550);
DISPLAY INVISIBLE (-6525 2550);
FORCEPROP 1 LAST PART_NUMBER CS27152FB03
J 0
(-6535 2250);
DISPLAY 0.489362 (-6535 2250);
PAINT SKYBLUE (-6535 2250);
DISPLAY INVISIBLE (-6535 2250);
FORCEADD Q_RES..1
(-6950 3200);
FORCEPROP 1 LAST LOCATION PR6500
J 0
(-6975 3250);
DISPLAY 0.489362 (-6975 3250);
PAINT SKYBLUE (-6975 3250);
FORCEPROP 0 LAST $SEC 1
J 0
(-7000 3275);
DISPLAY 0.680851 (-7000 3275);
PAINT MONO (-7000 3275);
DISPLAY INVISIBLE (-7000 3275);
FORCEPROP 0 LAST CDS_SEC 1
J 0
(-7000 3275);
DISPLAY 1.021277 (-7000 3275);
DISPLAY INVISIBLE (-7000 3275);
FORCEPROP 1 LASTPIN (-7050 3200) $PN 1
J 0
(-7038 3212);
DISPLAY 0.489362 (-7038 3212);
PAINT MONO (-7038 3212);
FORCEPROP 1 LASTPIN (-6850 3200) $PN 2
J 0
(-6888 3212);
DISPLAY 0.489362 (-6888 3212);
PAINT MONO (-6888 3212);
FORCEPROP 1 LAST WATTAGE 1/16W
J 0
(-6875 3100);
DISPLAY 0.489362 (-6875 3100);
PAINT SKYBLUE (-6875 3100);
FORCEPROP 1 LAST VALUE 0
J 2
(-7125 3225);
DISPLAY 0.489362 (-7125 3225);
PAINT SKYBLUE (-7125 3225);
FORCEPROP 1 LAST MATERIAL CHIP
J 0
(-7250 3100);
DISPLAY 0.489362 (-7250 3100);
PAINT SKYBLUE (-7250 3100);
FORCEPROP 1 LAST TOLERANCE 5%
J 0
(-6825 3225);
DISPLAY 0.489362 (-6825 3225);
PAINT SKYBLUE (-6825 3225);
FORCEPROP 1 LAST PACK_TYPE 0402LF
J 0
(-6875 3125);
DISPLAY 0.489362 (-6875 3125);
PAINT SKYBLUE (-6875 3125);
FORCEPROP 2 LAST CDS_LIB pure_quanta
J 0
(-6950 3200);
DISPLAY INVISIBLE (-6950 3200);
FORCEPROP 1 LAST PATH I21
J 0
(-7000 3350);
DISPLAY 0.978723 (-7000 3350);
PAINT WHITE (-7000 3350);
DISPLAY INVISIBLE (-7000 3350);
FORCEPROP 1 LAST PART_NUMBER CS00002JB13
J 0
(-7250 3125);
DISPLAY 0.489362 (-7250 3125);
PAINT SKYBLUE (-7250 3125);
DISPLAY INVISIBLE (-7250 3125);
FORCEADD Q_CAP..1
(-7350 3975);
FORCEPROP 1 LAST LOCATION PC6504
J 0
(-7300 4075);
DISPLAY 0.489362 (-7300 4075);
PAINT SKYBLUE (-7300 4075);
FORCEPROP 0 LAST $SEC 1
J 0
(-7300 4100);
DISPLAY 0.680851 (-7300 4100);
PAINT MONO (-7300 4100);
DISPLAY INVISIBLE (-7300 4100);
FORCEPROP 0 LAST CDS_SEC 1
J 0
(-7300 4125);
DISPLAY 0.680851 (-7300 4125);
DISPLAY INVISIBLE (-7300 4125);
FORCEPROP 1 LASTPIN (-7350 4075) $PN 1
J 0
(-7340 4055);
DISPLAY 0.489362 (-7340 4055);
PAINT MONO (-7340 4055);
FORCEPROP 1 LASTPIN (-7350 3875) $PN 2
J 0
(-7340 3855);
DISPLAY 0.489362 (-7340 3855);
PAINT MONO (-7340 3855);
FORCEPROP 1 LAST PACK_TYPE C0805
J 0
(-7300 3775);
DISPLAY 0.489362 (-7300 3775);
PAINT SKYBLUE (-7300 3775);
FORCEPROP 1 LAST TOLERANCE 20%
J 0
(-7300 3925);
DISPLAY 0.489362 (-7300 3925);
PAINT SKYBLUE (-7300 3925);
FORCEPROP 1 LAST MATERIAL X6S
J 0
(-7300 3875);
DISPLAY 0.489362 (-7300 3875);
PAINT SKYBLUE (-7300 3875);
FORCEPROP 1 LAST VALUE 22UF
J 0
(-7300 4025);
DISPLAY 0.489362 (-7300 4025);
PAINT SKYBLUE (-7300 4025);
FORCEPROP 1 LAST VOLTAGE 16V
J 0
(-7300 3975);
DISPLAY 0.489362 (-7300 3975);
PAINT SKYBLUE (-7300 3975);
FORCEPROP 2 LAST CDS_LIB pure_quanta
J 0
(-7350 3975);
DISPLAY INVISIBLE (-7350 3975);
FORCEPROP 1 LAST PATH I22
J 0
(-7300 4125);
DISPLAY 0.978723 (-7300 4125);
PAINT WHITE (-7300 4125);
DISPLAY INVISIBLE (-7300 4125);
FORCEPROP 1 LAST PART_NUMBER CH6223MEA01
J 0
(-7300 3825);
DISPLAY 0.489362 (-7300 3825);
PAINT SKYBLUE (-7300 3825);
DISPLAY INVISIBLE (-7300 3825);
FORCEADD Q_CAP..1
(-7150 3975);
FORCEPROP 1 LAST LOCATION PC6505
J 0
(-7100 4075);
DISPLAY 0.489362 (-7100 4075);
PAINT SKYBLUE (-7100 4075);
FORCEPROP 0 LAST $SEC 1
J 0
(-7100 4100);
DISPLAY 0.680851 (-7100 4100);
PAINT MONO (-7100 4100);
DISPLAY INVISIBLE (-7100 4100);
FORCEPROP 0 LAST CDS_SEC 1
J 0
(-7100 4100);
DISPLAY 1.021277 (-7100 4100);
DISPLAY INVISIBLE (-7100 4100);
FORCEPROP 1 LASTPIN (-7150 4075) $PN 1
J 0
(-7140 4055);
DISPLAY 0.489362 (-7140 4055);
PAINT MONO (-7140 4055);
FORCEPROP 1 LASTPIN (-7150 3875) $PN 2
J 0
(-7140 3855);
DISPLAY 0.489362 (-7140 3855);
PAINT MONO (-7140 3855);
FORCEPROP 1 LAST VOLTAGE 25V
J 0
(-7100 3975);
DISPLAY 0.489362 (-7100 3975);
PAINT SKYBLUE (-7100 3975);
FORCEPROP 1 LAST VALUE 1UF
J 0
(-7100 4025);
DISPLAY 0.489362 (-7100 4025);
PAINT SKYBLUE (-7100 4025);
FORCEPROP 1 LAST PACK_TYPE C0402
J 0
(-7100 3775);
DISPLAY 0.489362 (-7100 3775);
PAINT SKYBLUE (-7100 3775);
FORCEPROP 1 LAST TOLERANCE 10%
J 0
(-7100 3925);
DISPLAY 0.489362 (-7100 3925);
PAINT SKYBLUE (-7100 3925);
FORCEPROP 1 LAST MATERIAL X6S
J 0
(-7100 3875);
DISPLAY 0.489362 (-7100 3875);
PAINT SKYBLUE (-7100 3875);
FORCEPROP 2 LAST CDS_LIB pure_quanta
J 0
(-7150 3975);
PAINT MONO (-7150 3975);
DISPLAY INVISIBLE (-7150 3975);
FORCEPROP 1 LAST PATH I23
J 0
(-7100 4125);
DISPLAY 0.978723 (-7100 4125);
PAINT WHITE (-7100 4125);
DISPLAY INVISIBLE (-7100 4125);
FORCEPROP 1 LAST PART_NUMBER CH5104KEB02
J 0
(-7100 3825);
DISPLAY 0.382979 (-7100 3825);
PAINT SKYBLUE (-7100 3825);
DISPLAY INVISIBLE (-7100 3825);
FORCEADD UNIVERSAL_GND..1
(-5000 2275);
FORCEPROP 3 LASTPIN (-5000 2325) SIG_NAME GND\g
J 0
(-4990 2335);
DISPLAY 0.659574 (-4990 2335);
PAINT MONO (-4990 2335);
DISPLAY INVISIBLE (-4990 2335);
FORCEPROP 2 LAST CDS_LIB pure_quanta_power
J 0
(-5000 2275);
DISPLAY INVISIBLE (-5000 2275);
FORCEPROP 1 LAST HDL_POWER GND
J 1
(-4975 2200);
DISPLAY 0.872340 (-4975 2200);
PAINT GREEN (-4975 2200);
DISPLAY INVISIBLE (-4975 2200);
FORCEPROP 1 LAST PATH I24
J 0
(-4925 2275);
DISPLAY 0.872340 (-4925 2275);
PAINT AQUA (-4925 2275);
DISPLAY INVISIBLE (-4925 2275);
FORCEADD UNIVERSAL_GND..1
(-4875 2275);
FORCEPROP 3 LASTPIN (-4875 2325) SIG_NAME GND\g
J 0
(-4865 2335);
DISPLAY 0.659574 (-4865 2335);
PAINT MONO (-4865 2335);
DISPLAY INVISIBLE (-4865 2335);
FORCEPROP 2 LAST CDS_LIB pure_quanta_power
J 0
(-4875 2275);
DISPLAY INVISIBLE (-4875 2275);
FORCEPROP 1 LAST HDL_POWER GND
J 1
(-4850 2200);
DISPLAY 0.872340 (-4850 2200);
PAINT GREEN (-4850 2200);
DISPLAY INVISIBLE (-4850 2200);
FORCEPROP 1 LAST PATH I25
J 0
(-4800 2275);
DISPLAY 0.872340 (-4800 2275);
PAINT AQUA (-4800 2275);
DISPLAY INVISIBLE (-4800 2275);
FORCEADD Q_CAP..1
(-4875 2525);
FORCEPROP 1 LAST LOCATION PC6518
J 0
(-4825 2600);
DISPLAY 0.489362 (-4825 2600);
PAINT SKYBLUE (-4825 2600);
FORCEPROP 0 LAST $SEC 1
J 0
(-4825 2650);
DISPLAY 0.680851 (-4825 2650);
PAINT MONO (-4825 2650);
DISPLAY INVISIBLE (-4825 2650);
FORCEPROP 2 LAST CDS_SEC 1
J 0
(-4825 2725);
DISPLAY 0.680851 (-4825 2725);
DISPLAY INVISIBLE (-4825 2725);
FORCEPROP 1 LASTPIN (-4875 2625) $PN 1
J 0
(-4865 2605);
DISPLAY 0.489362 (-4865 2605);
PAINT MONO (-4865 2605);
FORCEPROP 1 LASTPIN (-4875 2425) $PN 2
J 0
(-4865 2405);
DISPLAY 0.489362 (-4865 2405);
PAINT MONO (-4865 2405);
FORCEPROP 1 LAST VOLTAGE 25V
J 0
(-4825 2500);
DISPLAY 0.489362 (-4825 2500);
PAINT SKYBLUE (-4825 2500);
FORCEPROP 1 LAST TOLERANCE 10%
J 0
(-4825 2450);
DISPLAY 0.489362 (-4825 2450);
PAINT SKYBLUE (-4825 2450);
FORCEPROP 1 LAST MATERIAL X7R
J 0
(-4825 2400);
DISPLAY 0.489362 (-4825 2400);
PAINT SKYBLUE (-4825 2400);
FORCEPROP 1 LAST VALUE 0.1UF
J 0
(-4825 2550);
DISPLAY 0.489362 (-4825 2550);
PAINT SKYBLUE (-4825 2550);
FORCEPROP 1 LAST PACK_TYPE 0402
J 0
(-4825 2300);
DISPLAY 0.489362 (-4825 2300);
PAINT SKYBLUE (-4825 2300);
FORCEPROP 2 LAST CDS_LIB pure_quanta
J 0
(-4875 2525);
DISPLAY INVISIBLE (-4875 2525);
FORCEPROP 1 LAST PATH I26
J 0
(-4825 2675);
DISPLAY 0.978723 (-4825 2675);
PAINT WHITE (-4825 2675);
DISPLAY INVISIBLE (-4825 2675);
FORCEPROP 1 LAST PART_NUMBER CH4104K1B00
J 0
(-4825 2350);
DISPLAY 0.489362 (-4825 2350);
PAINT SKYBLUE (-4825 2350);
DISPLAY INVISIBLE (-4825 2350);
FORCEADD UNIVERSAL_GND..1
(-4425 2250);
FORCEPROP 3 LASTPIN (-4425 2300) SIG_NAME GND\g
J 0
(-4415 2310);
DISPLAY 0.659574 (-4415 2310);
PAINT MONO (-4415 2310);
DISPLAY INVISIBLE (-4415 2310);
FORCEPROP 2 LAST CDS_LIB pure_quanta_power
J 0
(-4425 2250);
DISPLAY INVISIBLE (-4425 2250);
FORCEPROP 1 LAST HDL_POWER GND
J 1
(-4400 2175);
DISPLAY 0.872340 (-4400 2175);
PAINT GREEN (-4400 2175);
DISPLAY INVISIBLE (-4400 2175);
FORCEPROP 1 LAST PATH I27
J 0
(-4350 2250);
DISPLAY 0.872340 (-4350 2250);
PAINT AQUA (-4350 2250);
DISPLAY INVISIBLE (-4350 2250);
FORCEADD Q_RES..2
(-4575 4200);
FORCEPROP 1 LAST LOCATION R6505
J 0
(-4530 4325);
DISPLAY 0.489362 (-4530 4325);
PAINT SKYBLUE (-4530 4325);
FORCEPROP 2 LAST SEC 1
J 0
(-4524 4429);
DISPLAY 0.680851 (-4524 4429);
PAINT MONO (-4524 4429);
DISPLAY INVISIBLE (-4524 4429);
FORCEPROP 1 LASTPIN (-4575 4300) $PN 1
J 0
(-4570 4262);
DISPLAY 0.489362 (-4570 4262);
FORCEPROP 1 LASTPIN (-4575 4100) $PN 2
J 0
(-4570 4110);
DISPLAY 0.489362 (-4570 4110);
FORCEPROP 1 LAST MATERIAL CHIP
J 0
(-4535 4125);
DISPLAY 0.489362 (-4535 4125);
PAINT SKYBLUE (-4535 4125);
FORCEPROP 1 LAST TOLERANCE 5%
J 0
(-4530 4225);
DISPLAY 0.489362 (-4530 4225);
PAINT SKYBLUE (-4530 4225);
FORCEPROP 1 LAST VALUE 10K
J 0
(-4530 4275);
DISPLAY 0.489362 (-4530 4275);
PAINT SKYBLUE (-4530 4275);
FORCEPROP 1 LAST PACK_TYPE 0402LF
J 0
(-4535 4025);
DISPLAY 0.489362 (-4535 4025);
PAINT SKYBLUE (-4535 4025);
FORCEPROP 1 LAST WATTAGE 1/16W
J 0
(-4535 4175);
DISPLAY 0.489362 (-4535 4175);
PAINT SKYBLUE (-4535 4175);
FORCEPROP 2 LAST SEC_TYPE 0402LF
J 0
(-4524 4429);
DISPLAY 1.021277 (-4524 4429);
DISPLAY INVISIBLE (-4524 4429);
FORCEPROP 2 LAST CDS_LIB pure_quanta
R 3
J 0
(-4575 4200);
PAINT MONO (-4575 4200);
DISPLAY INVISIBLE (-4575 4200);
FORCEPROP 1 LAST PATH I28
J 0
(-4525 4375);
DISPLAY 0.978723 (-4525 4375);
PAINT WHITE (-4525 4375);
DISPLAY INVISIBLE (-4525 4375);
FORCEPROP 1 LAST PART_NUMBER CS31002JB08
J 0
(-4535 4075);
DISPLAY 0.489362 (-4535 4075);
PAINT SKYBLUE (-4535 4075);
DISPLAY INVISIBLE (-4535 4075);
FORCEADD Q_RES..1
(-4450 3700);
FORCEPROP 1 LAST LOCATION PR6800
J 0
(-4500 3750);
DISPLAY 0.489362 (-4500 3750);
PAINT SKYBLUE (-4500 3750);
FORCEPROP 0 LAST $SEC 1
J 0
(-4500 3775);
DISPLAY 0.680851 (-4500 3775);
PAINT MONO (-4500 3775);
DISPLAY INVISIBLE (-4500 3775);
FORCEPROP 0 LAST CDS_SEC 1
J 0
(-4500 3775);
DISPLAY 0.680851 (-4500 3775);
DISPLAY INVISIBLE (-4500 3775);
FORCEPROP 1 LASTPIN (-4550 3700) $PN 1
J 0
(-4538 3712);
DISPLAY 0.787234 (-4538 3712);
PAINT MONO (-4538 3712);
FORCEPROP 1 LASTPIN (-4350 3700) $PN 2
J 0
(-4388 3712);
DISPLAY 0.787234 (-4388 3712);
PAINT MONO (-4388 3712);
FORCEPROP 1 LAST VALUE 2.2
J 2
(-4400 3650);
DISPLAY 0.489362 (-4400 3650);
PAINT SKYBLUE (-4400 3650);
FORCEPROP 1 LAST PACK_TYPE 0402LF
J 0
(-4375 3650);
DISPLAY 0.489362 (-4375 3650);
PAINT SKYBLUE (-4375 3650);
FORCEPROP 1 LAST MATERIAL CHIP
J 0
(-4350 3625);
DISPLAY 0.489362 (-4350 3625);
PAINT SKYBLUE (-4350 3625);
FORCEPROP 2 LAST CDS_LIB pure_quanta
J 0
(-4450 3700);
DISPLAY INVISIBLE (-4450 3700);
FORCEPROP 1 LAST WATTAGE 1/16W
J 2
(-3876 3718);
DISPLAY 0.978723 (-3876 3718);
PAINT SKYBLUE (-3876 3718);
DISPLAY INVISIBLE (-3876 3718);
FORCEPROP 1 LAST TOLERANCE 1%
J 0
(-4330 3719);
DISPLAY 0.978723 (-4330 3719);
PAINT SKYBLUE (-4330 3719);
DISPLAY INVISIBLE (-4330 3719);
FORCEPROP 1 LAST PATH I29
J 0
(-4500 3850);
DISPLAY 0.978723 (-4500 3850);
PAINT WHITE (-4500 3850);
DISPLAY INVISIBLE (-4500 3850);
FORCEPROP 1 LAST PART_NUMBER CS-2202FB01
J 0
(-4750 3650);
DISPLAY 0.489362 (-4750 3650);
PAINT SKYBLUE (-4750 3650);
DISPLAY INVISIBLE (-4750 3650);
FORCEADD UNIVERSAL_GND..1
(-9100 3650);
FORCEPROP 3 LASTPIN (-9100 3700) SIG_NAME GND\g
J 0
(-9090 3710);
DISPLAY 0.659574 (-9090 3710);
PAINT MONO (-9090 3710);
DISPLAY INVISIBLE (-9090 3710);
FORCEPROP 2 LAST CDS_LIB pure_quanta_power
J 0
(-9100 3650);
DISPLAY INVISIBLE (-9100 3650);
FORCEPROP 1 LAST HDL_POWER GND
J 1
(-9075 3575);
DISPLAY 0.872340 (-9075 3575);
PAINT GREEN (-9075 3575);
DISPLAY INVISIBLE (-9075 3575);
FORCEPROP 1 LAST PATH I3
J 0
(-9025 3650);
DISPLAY 0.872340 (-9025 3650);
PAINT AQUA (-9025 3650);
DISPLAY INVISIBLE (-9025 3650);
FORCEADD UNIVERSAL_POWER..1
(-4575 4475);
FORCEPROP 3 LASTPIN (-4575 4425) SIG_NAME P3V3_AUX\g
J 0
(-4565 4435);
DISPLAY 0.659574 (-4565 4435);
PAINT MONO (-4565 4435);
DISPLAY INVISIBLE (-4565 4435);
FORCEPROP 1 LAST HDL_POWER P3V3_AUX
J 1
(-4575 4525);
DISPLAY 0.489362 (-4575 4525);
PAINT GREEN (-4575 4525);
FORCEPROP 2 LAST CDS_LIB mstr_symbols
J 0
(-4575 4475);
DISPLAY INVISIBLE (-4575 4475);
FORCEPROP 1 LAST PATH I30
J 0
(-4525 4500);
DISPLAY 0.872340 (-4525 4500);
PAINT AQUA (-4525 4500);
DISPLAY INVISIBLE (-4525 4500);
FORCEADD UNIVERSAL_GND..1
(-4025 2175);
FORCEPROP 3 LASTPIN (-4025 2225) SIG_NAME GND\g
J 0
(-4015 2235);
DISPLAY 0.659574 (-4015 2235);
PAINT MONO (-4015 2235);
DISPLAY INVISIBLE (-4015 2235);
FORCEPROP 2 LAST CDS_LIB pure_quanta_power
J 0
(-4025 2175);
DISPLAY INVISIBLE (-4025 2175);
FORCEPROP 1 LAST HDL_POWER GND
J 1
(-4000 2100);
DISPLAY 0.872340 (-4000 2100);
PAINT GREEN (-4000 2100);
DISPLAY INVISIBLE (-4000 2100);
FORCEPROP 1 LAST PATH I31
J 0
(-3950 2175);
DISPLAY 0.872340 (-3950 2175);
PAINT AQUA (-3950 2175);
DISPLAY INVISIBLE (-3950 2175);
FORCEADD Q_CAP..1
(-4025 3550);
FORCEPROP 1 LAST LOCATION PC6507
J 0
(-3975 3725);
DISPLAY 0.489362 (-3975 3725);
PAINT SKYBLUE (-3975 3725);
FORCEPROP 2 LAST SEC 1
J 0
(-3951 3769);
DISPLAY 0.680851 (-3951 3769);
PAINT MONO (-3951 3769);
DISPLAY INVISIBLE (-3951 3769);
FORCEPROP 1 LASTPIN (-4025 3650) $PN 1
J 0
(-4015 3630);
DISPLAY 0.489362 (-4015 3630);
FORCEPROP 1 LASTPIN (-4025 3450) $PN 2
J 0
(-4015 3430);
DISPLAY 0.489362 (-4015 3430);
FORCEPROP 1 LAST MATERIAL X7R
J 0
(-3975 3525);
DISPLAY 0.489362 (-3975 3525);
PAINT SKYBLUE (-3975 3525);
FORCEPROP 1 LAST TOLERANCE 10%
J 0
(-3975 3575);
DISPLAY 0.489362 (-3975 3575);
PAINT SKYBLUE (-3975 3575);
FORCEPROP 1 LAST VOLTAGE 16V
J 0
(-3975 3625);
DISPLAY 0.489362 (-3975 3625);
PAINT SKYBLUE (-3975 3625);
FORCEPROP 1 LAST PACK_TYPE 0402
J 0
(-3975 3425);
DISPLAY 0.489362 (-3975 3425);
PAINT SKYBLUE (-3975 3425);
FORCEPROP 1 LAST VALUE 0.22UF
J 0
(-3975 3675);
DISPLAY 0.489362 (-3975 3675);
PAINT SKYBLUE (-3975 3675);
FORCEPROP 2 LAST CDS_LIB pure_quanta
J 0
(-4025 3550);
PAINT MONO (-4025 3550);
DISPLAY INVISIBLE (-4025 3550);
FORCEPROP 2 LAST SEC_TYPE 0402
J 0
(-3951 3769);
DISPLAY 1.021277 (-3951 3769);
DISPLAY INVISIBLE (-3951 3769);
FORCEPROP 1 LAST PATH I32
J 0
(-3975 3700);
DISPLAY 0.978723 (-3975 3700);
PAINT WHITE (-3975 3700);
DISPLAY INVISIBLE (-3975 3700);
FORCEPROP 1 LAST PART_NUMBER CH4223K1B00
J 0
(-3975 3475);
DISPLAY 0.489362 (-3975 3475);
PAINT SKYBLUE (-3975 3475);
DISPLAY INVISIBLE (-3975 3475);
FORCEADD Q_RES..2
(-4025 2425);
FORCEPROP 1 LAST LOCATION PR6507
J 0
(-3980 2550);
DISPLAY 0.489362 (-3980 2550);
PAINT SKYBLUE (-3980 2550);
FORCEPROP 2 LAST $SEC 1
J 0
(-3975 2650);
DISPLAY 0.680851 (-3975 2650);
PAINT MONO (-3975 2650);
DISPLAY INVISIBLE (-3975 2650);
FORCEPROP 2 LAST CDS_SEC 1
J 0
(-3975 2650);
DISPLAY 0.680851 (-3975 2650);
DISPLAY INVISIBLE (-3975 2650);
FORCEPROP 1 LASTPIN (-4025 2525) $PN 1
J 0
(-4020 2487);
DISPLAY 0.489362 (-4020 2487);
FORCEPROP 1 LASTPIN (-4025 2325) $PN 2
J 0
(-4020 2335);
DISPLAY 0.489362 (-4020 2335);
FORCEPROP 1 LAST VALUE 10K
J 0
(-3980 2500);
DISPLAY 0.489362 (-3980 2500);
PAINT SKYBLUE (-3980 2500);
FORCEPROP 1 LAST TOLERANCE 1%
J 0
(-3980 2450);
DISPLAY 0.489362 (-3980 2450);
PAINT SKYBLUE (-3980 2450);
FORCEPROP 1 LAST MATERIAL CHIP
J 0
(-3985 2350);
DISPLAY 0.489362 (-3985 2350);
PAINT SKYBLUE (-3985 2350);
FORCEPROP 1 LAST PACK_TYPE 0402LF
J 0
(-3985 2250);
DISPLAY 0.489362 (-3985 2250);
PAINT SKYBLUE (-3985 2250);
FORCEPROP 1 LAST WATTAGE 1/16W
J 0
(-3985 2400);
DISPLAY 0.489362 (-3985 2400);
PAINT SKYBLUE (-3985 2400);
FORCEPROP 2 LAST CDS_LIB pure_quanta
J 0
(-4025 2425);
DISPLAY INVISIBLE (-4025 2425);
FORCEPROP 1 LAST PATH I33
J 0
(-3975 2600);
DISPLAY 0.978723 (-3975 2600);
PAINT WHITE (-3975 2600);
DISPLAY INVISIBLE (-3975 2600);
FORCEPROP 1 LAST PART_NUMBER CS31002FB08
J 0
(-3985 2300);
DISPLAY 0.489362 (-3985 2300);
PAINT SKYBLUE (-3985 2300);
DISPLAY INVISIBLE (-3985 2300);
FORCEADD Q_CAP..2
(-3450 2625);
FORCEPROP 1 LAST LOCATION PC6515
J 1
(-3450 2700);
DISPLAY 0.489362 (-3450 2700);
PAINT SKYBLUE (-3450 2700);
FORCEPROP 0 LAST $SEC 1
J 0
(-3450 2775);
DISPLAY 0.680851 (-3450 2775);
PAINT MONO (-3450 2775);
DISPLAY INVISIBLE (-3450 2775);
FORCEPROP 0 LAST CDS_SEC 1
J 0
(-3450 2775);
DISPLAY 0.680851 (-3450 2775);
DISPLAY INVISIBLE (-3450 2775);
FORCEPROP 1 LASTPIN (-3550 2625) $PN 1
J 0
(-3560 2640);
DISPLAY 0.489362 (-3560 2640);
PAINT MONO (-3560 2640);
FORCEPROP 1 LASTPIN (-3350 2625) $PN 2
J 0
(-3365 2640);
DISPLAY 0.489362 (-3365 2640);
PAINT MONO (-3365 2640);
FORCEPROP 1 LAST TOLERANCE 5%
J 2
(-3575 2500);
DISPLAY 0.489362 (-3575 2500);
PAINT SKYBLUE (-3575 2500);
FORCEPROP 1 LAST VALUE 150PF
J 2
(-3525 2675);
DISPLAY 0.489362 (-3525 2675);
PAINT SKYBLUE (-3525 2675);
FORCEPROP 1 LAST PACK_TYPE 0402
J 1
(-3325 2500);
DISPLAY 0.489362 (-3325 2500);
PAINT SKYBLUE (-3325 2500);
FORCEPROP 1 LAST VOLTAGE 50V
J 0
(-3350 2675);
DISPLAY 0.489362 (-3350 2675);
PAINT SKYBLUE (-3350 2675);
FORCEPROP 1 LAST MATERIAL NPO
J 0
(-3375 2550);
DISPLAY 0.489362 (-3375 2550);
PAINT SKYBLUE (-3375 2550);
FORCEPROP 2 LAST CDS_LIB pure_quanta
J 0
(-3450 2625);
DISPLAY INVISIBLE (-3450 2625);
FORCEPROP 1 LAST PATH I34
J 0
(-3450 2825);
DISPLAY 0.978723 (-3450 2825);
PAINT WHITE (-3450 2825);
DISPLAY INVISIBLE (-3450 2825);
FORCEPROP 1 LAST PART_NUMBER TMP_QCH11506JB08
J 1
(-3650 2550);
DISPLAY 0.489362 (-3650 2550);
PAINT SKYBLUE (-3650 2550);
DISPLAY INVISIBLE (-3650 2550);
FORCEADD Q_RES..1
(-3450 2950);
FORCEPROP 1 LAST LOCATION PR6505
J 0
(-3500 3000);
DISPLAY 0.489362 (-3500 3000);
PAINT SKYBLUE (-3500 3000);
FORCEPROP 2 LAST $SEC 1
J 0
(-3477 3163);
DISPLAY 0.680851 (-3477 3163);
PAINT MONO (-3477 3163);
DISPLAY INVISIBLE (-3477 3163);
FORCEPROP 2 LAST CDS_SEC 1
J 0
(-3477 3163);
DISPLAY 0.680851 (-3477 3163);
DISPLAY INVISIBLE (-3477 3163);
FORCEPROP 1 LASTPIN (-3550 2950) $PN 1
J 0
(-3538 2962);
DISPLAY 0.489362 (-3538 2962);
FORCEPROP 1 LASTPIN (-3350 2950) $PN 2
J 0
(-3388 2962);
DISPLAY 0.489362 (-3388 2962);
FORCEPROP 1 LAST PACK_TYPE 0402LF
J 0
(-3275 2900);
DISPLAY 0.489362 (-3275 2900);
PAINT SKYBLUE (-3275 2900);
FORCEPROP 1 LAST MATERIAL CHIP
J 0
(-3275 3000);
DISPLAY 0.489362 (-3275 3000);
PAINT SKYBLUE (-3275 3000);
FORCEPROP 1 LAST VALUE 20K
J 2
(-3575 3000);
DISPLAY 0.489362 (-3575 3000);
PAINT SKYBLUE (-3575 3000);
FORCEPROP 1 LAST TOLERANCE 1%
J 0
(-3330 2969);
DISPLAY 0.978723 (-3330 2969);
PAINT SKYBLUE (-3330 2969);
DISPLAY INVISIBLE (-3330 2969);
FORCEPROP 1 LAST WATTAGE 1/16W
J 2
(-2876 2968);
DISPLAY 0.978723 (-2876 2968);
PAINT SKYBLUE (-2876 2968);
DISPLAY INVISIBLE (-2876 2968);
FORCEPROP 2 LAST CDS_LIB pure_quanta
J 0
(-3450 2950);
DISPLAY INVISIBLE (-3450 2950);
FORCEPROP 1 LAST PATH I35
J 0
(-3500 3100);
DISPLAY 0.978723 (-3500 3100);
PAINT WHITE (-3500 3100);
DISPLAY INVISIBLE (-3500 3100);
FORCEPROP 1 LAST PART_NUMBER CS32002FB06
J 0
(-3700 2900);
DISPLAY 0.489362 (-3700 2900);
PAINT SKYBLUE (-3700 2900);
DISPLAY INVISIBLE (-3700 2900);
FORCEADD Q_INDUCTOR..1
(-3450 3425);
FORCEPROP 1 LAST LOCATION PL6501
J 0
(-3575 3585);
DISPLAY 0.489362 (-3575 3585);
PAINT SKYBLUE (-3575 3585);
FORCEPROP 2 LAST $SEC 1
J 0
(-3575 3725);
DISPLAY 0.680851 (-3575 3725);
PAINT MONO (-3575 3725);
DISPLAY INVISIBLE (-3575 3725);
FORCEPROP 2 LAST CDS_SEC 1
J 0
(-3575 3725);
DISPLAY 0.680851 (-3575 3725);
DISPLAY INVISIBLE (-3575 3725);
FORCEPROP 2 LASTPIN (-3550 3400) $PN 1
J 2
(-3560 3410);
DISPLAY 0.489362 (-3560 3410);
FORCEPROP 2 LASTPIN (-3350 3400) $PN 2
J 0
(-3340 3410);
DISPLAY 0.489362 (-3340 3410);
FORCEPROP 1 LAST MATERIAL IND
J 0
(-3575 3480);
DISPLAY 0.489362 (-3575 3480);
PAINT SKYBLUE (-3575 3480);
FORCEPROP 2 LAST VALUE 1UH
J 0
(-3575 3625);
DISPLAY 0.489362 (-3575 3625);
PAINT SKYBLUE (-3575 3625);
FORCEPROP 2 LAST PACK_TYPE SMLF
J 0
(-3575 3675);
DISPLAY 0.489362 (-3575 3675);
PAINT SKYBLUE (-3575 3675);
FORCEPROP 1 LAST NEEDS_NO_SIZE TRUE
J 0
(-3450 3425);
DISPLAY 0.468085 (-3450 3425);
PAINT GREEN (-3450 3425);
DISPLAY INVISIBLE (-3450 3425);
FORCEPROP 2 LAST CDS_LIB pure_quanta
J 0
(-3450 3425);
DISPLAY INVISIBLE (-3450 3425);
FORCEPROP 1 LAST PATH I36
J 0
(-3375 3480);
DISPLAY 0.723404 (-3375 3480);
PAINT GREEN (-3375 3480);
DISPLAY INVISIBLE (-3375 3480);
FORCEPROP 1 LAST PART_NUMBER CV-10U0MZ01
J 0
(-3575 3535);
DISPLAY 0.489362 (-3575 3535);
PAINT SKYBLUE (-3575 3535);
DISPLAY INVISIBLE (-3575 3535);
FORCEADD Q_RES..1
(-3525 3900);
FORCEPROP 1 LAST LOCATION R6506
J 0
(-3400 3900);
DISPLAY 0.489362 (-3400 3900);
PAINT SKYBLUE (-3400 3900);
FORCEPROP 0 LAST $SEC 1
J 2
(-3400 3950);
DISPLAY 0.680851 (-3400 3950);
PAINT MONO (-3400 3950);
DISPLAY INVISIBLE (-3400 3950);
FORCEPROP 0 LAST CDS_SEC 1
J 2
(-3400 3950);
DISPLAY 1.021277 (-3400 3950);
DISPLAY INVISIBLE (-3400 3950);
FORCEPROP 1 LASTPIN (-3625 3900) $PN 1
J 0
(-3613 3912);
DISPLAY 0.489362 (-3613 3912);
PAINT MONO (-3613 3912);
FORCEPROP 1 LASTPIN (-3425 3900) $PN 2
J 0
(-3463 3912);
DISPLAY 0.489362 (-3463 3912);
PAINT MONO (-3463 3912);
FORCEPROP 1 LAST VALUE 33
J 2
(-3650 3900);
DISPLAY 0.489362 (-3650 3900);
PAINT SKYBLUE (-3650 3900);
FORCEPROP 2 LAST CDS_LIB pure_quanta
J 2
(-3525 3900);
DISPLAY INVISIBLE (-3525 3900);
FORCEPROP 2 LAST BOM_COST MEM
J 2
(-3500 4050);
DISPLAY 0.744681 (-3500 4050);
PAINT WHITE (-3500 4050);
DISPLAY INVISIBLE (-3500 4050);
FORCEPROP 1 LAST WATTAGE 1/16W
J 2
(-3600 3825);
DISPLAY 0.489362 (-3600 3825);
PAINT SKYBLUE (-3600 3825);
DISPLAY INVISIBLE (-3600 3825);
FORCEPROP 1 LAST MATERIAL CHIP
J 2
(-3350 3875);
DISPLAY 0.489362 (-3350 3875);
PAINT SKYBLUE (-3350 3875);
DISPLAY INVISIBLE (-3350 3875);
FORCEPROP 1 LAST TOLERANCE 5%
J 0
(-3650 3875);
DISPLAY 0.489362 (-3650 3875);
PAINT SKYBLUE (-3650 3875);
DISPLAY INVISIBLE (-3650 3875);
FORCEPROP 1 LAST PACK_TYPE 0402LF
J 2
(-3350 3825);
DISPLAY 0.489362 (-3350 3825);
PAINT SKYBLUE (-3350 3825);
DISPLAY INVISIBLE (-3350 3825);
FORCEPROP 1 LAST PATH I37
J 0
(-3575 4050);
DISPLAY 0.978723 (-3575 4050);
PAINT WHITE (-3575 4050);
DISPLAY INVISIBLE (-3575 4050);
FORCEPROP 1 LAST PART_NUMBER CS03302JB10
J 2
(-3425 3950);
DISPLAY 0.489362 (-3425 3950);
PAINT SKYBLUE (-3425 3950);
DISPLAY INVISIBLE (-3425 3950);
FORCEADD Q_CAP..1
(-2800 3150);
FORCEPROP 1 LAST LOCATION PC6508
J 0
(-2750 3250);
DISPLAY 0.489362 (-2750 3250);
PAINT SKYBLUE (-2750 3250);
FORCEPROP 0 LAST $SEC 1
J 0
(-2750 3275);
DISPLAY 0.680851 (-2750 3275);
PAINT MONO (-2750 3275);
DISPLAY INVISIBLE (-2750 3275);
FORCEPROP 0 LAST CDS_SEC 1
J 0
(-2750 3275);
DISPLAY 1.021277 (-2750 3275);
DISPLAY INVISIBLE (-2750 3275);
FORCEPROP 1 LASTPIN (-2800 3250) $PN 1
J 0
(-2790 3230);
DISPLAY 0.489362 (-2790 3230);
PAINT MONO (-2790 3230);
FORCEPROP 1 LASTPIN (-2800 3050) $PN 2
J 0
(-2790 3030);
DISPLAY 0.489362 (-2790 3030);
PAINT MONO (-2790 3030);
FORCEPROP 1 LAST PACK_TYPE C0805
J 0
(-2750 2950);
DISPLAY 0.489362 (-2750 2950);
PAINT SKYBLUE (-2750 2950);
FORCEPROP 1 LAST VOLTAGE 4V
J 0
(-2750 3150);
DISPLAY 0.489362 (-2750 3150);
PAINT SKYBLUE (-2750 3150);
FORCEPROP 1 LAST TOLERANCE 20%
J 0
(-2750 3100);
DISPLAY 0.489362 (-2750 3100);
PAINT SKYBLUE (-2750 3100);
FORCEPROP 1 LAST MATERIAL X6S
J 0
(-2750 3050);
DISPLAY 0.489362 (-2750 3050);
PAINT SKYBLUE (-2750 3050);
FORCEPROP 1 LAST VALUE 22UF
J 0
(-2750 3200);
DISPLAY 0.489362 (-2750 3200);
PAINT SKYBLUE (-2750 3200);
FORCEPROP 2 LAST CDS_LIB pure_quanta
J 0
(-2800 3150);
DISPLAY INVISIBLE (-2800 3150);
FORCEPROP 1 LAST PATH I38
J 0
(-2750 3300);
DISPLAY 0.978723 (-2750 3300);
PAINT WHITE (-2750 3300);
DISPLAY INVISIBLE (-2750 3300);
FORCEPROP 1 LAST PART_NUMBER CH622KMEA03
J 0
(-2750 3000);
DISPLAY 0.489362 (-2750 3000);
PAINT SKYBLUE (-2750 3000);
DISPLAY INVISIBLE (-2750 3000);
FORCEADD Q_CAP..1
(-2425 3150);
FORCEPROP 1 LAST LOCATION PC6509
J 0
(-2375 3250);
DISPLAY 0.489362 (-2375 3250);
PAINT SKYBLUE (-2375 3250);
FORCEPROP 0 LAST $SEC 1
J 0
(-2375 3300);
DISPLAY 0.680851 (-2375 3300);
PAINT MONO (-2375 3300);
DISPLAY INVISIBLE (-2375 3300);
FORCEPROP 0 LAST CDS_SEC 1
J 0
(-2375 3300);
DISPLAY 1.021277 (-2375 3300);
DISPLAY INVISIBLE (-2375 3300);
FORCEPROP 1 LASTPIN (-2425 3250) $PN 1
J 0
(-2415 3230);
DISPLAY 0.489362 (-2415 3230);
PAINT MONO (-2415 3230);
FORCEPROP 1 LASTPIN (-2425 3050) $PN 2
J 0
(-2415 3030);
DISPLAY 0.489362 (-2415 3030);
PAINT MONO (-2415 3030);
FORCEPROP 1 LAST VOLTAGE 4V
J 0
(-2375 3150);
DISPLAY 0.489362 (-2375 3150);
PAINT SKYBLUE (-2375 3150);
FORCEPROP 1 LAST VALUE 22UF
J 0
(-2375 3200);
DISPLAY 0.489362 (-2375 3200);
PAINT SKYBLUE (-2375 3200);
FORCEPROP 1 LAST PACK_TYPE C0805
J 0
(-2375 3000);
DISPLAY 0.489362 (-2375 3000);
PAINT SKYBLUE (-2375 3000);
FORCEPROP 1 LAST MATERIAL X6S
J 0
(-2375 3050);
DISPLAY 0.489362 (-2375 3050);
PAINT SKYBLUE (-2375 3050);
FORCEPROP 1 LAST TOLERANCE 20%
J 0
(-2375 3100);
DISPLAY 0.489362 (-2375 3100);
PAINT SKYBLUE (-2375 3100);
FORCEPROP 2 LAST CDS_LIB pure_quanta
J 0
(-2425 3150);
DISPLAY INVISIBLE (-2425 3150);
FORCEPROP 1 LAST PATH I39
J 0
(-2375 3300);
DISPLAY 0.978723 (-2375 3300);
PAINT WHITE (-2375 3300);
DISPLAY INVISIBLE (-2375 3300);
FORCEPROP 1 LAST PART_NUMBER CH622KMEA03
J 0
(-2375 3000);
DISPLAY 0.489362 (-2375 3000);
PAINT SKYBLUE (-2375 3000);
DISPLAY INVISIBLE (-2375 3000);
FORCEADD Q_CAP..1
(-9100 3975);
FORCEPROP 1 LAST LOCATION PC6500
J 0
(-9050 4075);
DISPLAY 0.489362 (-9050 4075);
PAINT SKYBLUE (-9050 4075);
FORCEPROP 0 LAST $SEC 1
J 0
(-9050 4100);
DISPLAY 0.680851 (-9050 4100);
PAINT MONO (-9050 4100);
DISPLAY INVISIBLE (-9050 4100);
FORCEPROP 0 LAST CDS_SEC 1
J 0
(-9050 4100);
DISPLAY 0.680851 (-9050 4100);
DISPLAY INVISIBLE (-9050 4100);
FORCEPROP 1 LASTPIN (-9100 4075) $PN 1
J 0
(-9090 4055);
DISPLAY 0.787234 (-9090 4055);
PAINT MONO (-9090 4055);
FORCEPROP 1 LASTPIN (-9100 3875) $PN 2
J 0
(-9090 3855);
DISPLAY 0.787234 (-9090 3855);
PAINT MONO (-9090 3855);
FORCEPROP 1 LAST MATERIAL X6S
J 0
(-9050 3875);
DISPLAY 0.489362 (-9050 3875);
PAINT SKYBLUE (-9050 3875);
FORCEPROP 1 LAST TOLERANCE 10%
J 0
(-9050 3925);
DISPLAY 0.489362 (-9050 3925);
PAINT SKYBLUE (-9050 3925);
FORCEPROP 1 LAST VOLTAGE 25V
J 0
(-9050 3975);
DISPLAY 0.489362 (-9050 3975);
PAINT SKYBLUE (-9050 3975);
FORCEPROP 1 LAST PACK_TYPE C0402
J 0
(-9050 3775);
DISPLAY 0.489362 (-9050 3775);
PAINT SKYBLUE (-9050 3775);
FORCEPROP 1 LAST VALUE 0.1UF
J 0
(-9050 4025);
DISPLAY 0.489362 (-9050 4025);
PAINT SKYBLUE (-9050 4025);
FORCEPROP 2 LAST CDS_LIB pure_quanta
J 0
(-9100 3975);
DISPLAY INVISIBLE (-9100 3975);
FORCEPROP 1 LAST PATH I4
J 0
(-9050 4125);
DISPLAY 0.978723 (-9050 4125);
PAINT WHITE (-9050 4125);
DISPLAY INVISIBLE (-9050 4125);
FORCEPROP 1 LAST PART_NUMBER CH4104KEB00
J 0
(-9050 3825);
DISPLAY 0.489362 (-9050 3825);
PAINT SKYBLUE (-9050 3825);
DISPLAY INVISIBLE (-9050 3825);
FORCEADD Q_CAP..1
(-2150 3150);
FORCEPROP 1 LAST LOCATION PC6510
J 0
(-2100 3250);
DISPLAY 0.489362 (-2100 3250);
PAINT SKYBLUE (-2100 3250);
FORCEPROP 0 LAST $SEC 1
J 0
(-2100 3300);
DISPLAY 0.680851 (-2100 3300);
PAINT MONO (-2100 3300);
DISPLAY INVISIBLE (-2100 3300);
FORCEPROP 0 LAST CDS_SEC 1
J 0
(-2100 3300);
DISPLAY 1.021277 (-2100 3300);
DISPLAY INVISIBLE (-2100 3300);
FORCEPROP 1 LASTPIN (-2150 3250) $PN 1
J 0
(-2140 3230);
DISPLAY 0.489362 (-2140 3230);
PAINT MONO (-2140 3230);
FORCEPROP 1 LASTPIN (-2150 3050) $PN 2
J 0
(-2140 3030);
DISPLAY 0.489362 (-2140 3030);
PAINT MONO (-2140 3030);
FORCEPROP 1 LAST VOLTAGE 4V
J 0
(-2100 3150);
DISPLAY 0.489362 (-2100 3150);
PAINT SKYBLUE (-2100 3150);
FORCEPROP 1 LAST VALUE 22UF
J 0
(-2100 3200);
DISPLAY 0.489362 (-2100 3200);
PAINT SKYBLUE (-2100 3200);
FORCEPROP 1 LAST TOLERANCE 20%
J 0
(-2100 3100);
DISPLAY 0.489362 (-2100 3100);
PAINT SKYBLUE (-2100 3100);
FORCEPROP 1 LAST MATERIAL X6S
J 0
(-2100 3050);
DISPLAY 0.489362 (-2100 3050);
PAINT SKYBLUE (-2100 3050);
FORCEPROP 1 LAST PACK_TYPE C0805
J 0
(-2100 3000);
DISPLAY 0.489362 (-2100 3000);
PAINT SKYBLUE (-2100 3000);
FORCEPROP 2 LAST CDS_LIB pure_quanta
J 0
(-2150 3150);
DISPLAY INVISIBLE (-2150 3150);
FORCEPROP 1 LAST PATH I40
J 0
(-2100 3300);
DISPLAY 0.978723 (-2100 3300);
PAINT WHITE (-2100 3300);
DISPLAY INVISIBLE (-2100 3300);
FORCEPROP 1 LAST PART_NUMBER CH622KMEA03
J 0
(-2100 3000);
DISPLAY 0.489362 (-2100 3000);
PAINT SKYBLUE (-2100 3000);
DISPLAY INVISIBLE (-2100 3000);
FORCEADD UNIVERSAL_GND..1
(-2725 3550);
FORCEPROP 3 LASTPIN (-2725 3600) SIG_NAME GND\g
J 0
(-2715 3610);
DISPLAY 0.659574 (-2715 3610);
PAINT MONO (-2715 3610);
DISPLAY INVISIBLE (-2715 3610);
FORCEPROP 2 LAST CDS_LIB pure_quanta_power
J 0
(-2725 3550);
DISPLAY INVISIBLE (-2725 3550);
FORCEPROP 1 LAST HDL_POWER GND
J 1
(-2700 3475);
DISPLAY 0.872340 (-2700 3475);
PAINT GREEN (-2700 3475);
DISPLAY INVISIBLE (-2700 3475);
FORCEPROP 1 LAST PATH I41
J 0
(-2650 3550);
DISPLAY 0.872340 (-2650 3550);
PAINT AQUA (-2650 3550);
DISPLAY INVISIBLE (-2650 3550);
FORCEADD Q_CAP..1
(-2725 3750);
FORCEPROP 1 LAST LOCATION C6758
J 0
(-2675 3850);
DISPLAY 0.638298 (-2675 3850);
FORCEPROP 0 LAST $SEC 1
J 0
(-2675 3900);
DISPLAY 0.680851 (-2675 3900);
PAINT MONO (-2675 3900);
DISPLAY INVISIBLE (-2675 3900);
FORCEPROP 0 LAST CDS_SEC 1
J 0
(-2675 3900);
DISPLAY 0.680851 (-2675 3900);
DISPLAY INVISIBLE (-2675 3900);
FORCEPROP 1 LASTPIN (-2725 3850) $PN 1
J 0
(-2715 3830);
DISPLAY 0.787234 (-2715 3830);
PAINT MONO (-2715 3830);
FORCEPROP 1 LASTPIN (-2725 3650) $PN 2
J 0
(-2715 3630);
DISPLAY 0.787234 (-2715 3630);
PAINT MONO (-2715 3630);
FORCEPROP 1 LAST VOLTAGE 50V
J 0
(-2675 3750);
DISPLAY 0.638298 (-2675 3750);
FORCEPROP 1 LAST VALUE 1000PF
J 0
(-2675 3800);
DISPLAY 0.638298 (-2675 3800);
FORCEPROP 1 LAST PACK_TYPE 0402
J 0
(-2675 3550);
DISPLAY 0.638298 (-2675 3550);
FORCEPROP 1 LAST MATERIAL X7R
J 0
(-2675 3650);
DISPLAY 0.638298 (-2675 3650);
FORCEPROP 1 LAST TOLERANCE 5%
J 0
(-2675 3700);
DISPLAY 0.638298 (-2675 3700);
FORCEPROP 2 LAST CDS_LIB pure_quanta
J 0
(-2725 3750);
DISPLAY INVISIBLE (-2725 3750);
FORCEPROP 1 LAST PATH I42
J 0
(-2675 3900);
DISPLAY 0.978723 (-2675 3900);
PAINT WHITE (-2675 3900);
DISPLAY INVISIBLE (-2675 3900);
FORCEPROP 1 LAST PART_NUMBER TMP_QCH21006JB10
J 0
(-2675 3600);
DISPLAY 0.638298 (-2675 3600);
DISPLAY INVISIBLE (-2675 3600);
FORCEADD OFFPAGE..2
(-2475 3900);
FORCEPROP 2 LAST $XR0 81 
J 0
(-2286 3900);
DISPLAY 0.638298 (-2286 3900);
PAINT MONO (-2286 3900);
FORCEPROP 2 LAST CDS_LIB standard
J 0
(-2475 3900);
DISPLAY INVISIBLE (-2475 3900);
FORCEPROP 2 LAST ROOM VR_CORE0_CTRL
J 2
(-2200 3950);
PAINT RED (-2200 3950);
DISPLAY INVISIBLE (-2200 3950);
FORCEPROP 1 LAST OFFPAGE TRUE
J 0
(-2150 3775);
DISPLAY 1.170213 (-2150 3775);
PAINT GREEN (-2150 3775);
DISPLAY INVISIBLE (-2150 3775);
FORCEPROP 1 LAST COMMENT_BODY TRUE
J 0
(-2520 3805);
DISPLAY 1.170213 (-2520 3805);
PAINT GREEN (-2520 3805);
DISPLAY INVISIBLE (-2520 3805);
FORCEPROP 2 LAST PATH I43
J 0
(-2300 3975);
DISPLAY 0.680851 (-2300 3975);
DISPLAY INVISIBLE (-2300 3975);
FORCEADD Q_CAP..1
(-1875 3150);
FORCEPROP 1 LAST LOCATION PC6511
J 0
(-1825 3250);
DISPLAY 0.489362 (-1825 3250);
PAINT SKYBLUE (-1825 3250);
FORCEPROP 0 LAST $SEC 1
J 0
(-1825 3300);
DISPLAY 0.680851 (-1825 3300);
PAINT MONO (-1825 3300);
DISPLAY INVISIBLE (-1825 3300);
FORCEPROP 0 LAST CDS_SEC 1
J 0
(-1825 3300);
DISPLAY 0.680851 (-1825 3300);
DISPLAY INVISIBLE (-1825 3300);
FORCEPROP 1 LASTPIN (-1875 3250) $PN 1
J 0
(-1865 3230);
DISPLAY 0.489362 (-1865 3230);
PAINT MONO (-1865 3230);
FORCEPROP 1 LASTPIN (-1875 3050) $PN 2
J 0
(-1865 3030);
DISPLAY 0.489362 (-1865 3030);
PAINT MONO (-1865 3030);
FORCEPROP 1 LAST VALUE 22UF
J 0
(-1825 3200);
DISPLAY 0.489362 (-1825 3200);
PAINT SKYBLUE (-1825 3200);
FORCEPROP 1 LAST VOLTAGE 4V
J 0
(-1825 3150);
DISPLAY 0.489362 (-1825 3150);
PAINT SKYBLUE (-1825 3150);
FORCEPROP 1 LAST TOLERANCE 20%
J 0
(-1825 3100);
DISPLAY 0.489362 (-1825 3100);
PAINT SKYBLUE (-1825 3100);
FORCEPROP 1 LAST MATERIAL X6S
J 0
(-1825 3050);
DISPLAY 0.489362 (-1825 3050);
PAINT RED (-1825 3050);
FORCEPROP 1 LAST PACK_TYPE C0805
J 0
(-1825 3000);
DISPLAY 0.489362 (-1825 3000);
PAINT SKYBLUE (-1825 3000);
FORCEPROP 2 LAST CDS_LIB pure_quanta
J 0
(-1875 3150);
DISPLAY INVISIBLE (-1875 3150);
FORCEPROP 1 LAST PATH I44
J 0
(-1825 3300);
DISPLAY 0.978723 (-1825 3300);
PAINT WHITE (-1825 3300);
DISPLAY INVISIBLE (-1825 3300);
FORCEPROP 1 LAST PART_NUMBER CH622KMEA03
J 0
(-1825 3000);
DISPLAY 0.489362 (-1825 3000);
PAINT SKYBLUE (-1825 3000);
DISPLAY INVISIBLE (-1825 3000);
FORCEADD Q_CAPP..1
(-1300 3150);
FORCEPROP 1 LAST LOCATION PC6513
J 0
(-1250 3250);
DISPLAY 0.489362 (-1250 3250);
PAINT SKYBLUE (-1250 3250);
FORCEPROP 0 LAST $SEC 1
J 0
(-1250 3275);
DISPLAY 0.680851 (-1250 3275);
PAINT MONO (-1250 3275);
DISPLAY INVISIBLE (-1250 3275);
FORCEPROP 0 LAST CDS_SEC 1
J 0
(-1250 3275);
DISPLAY 1.021277 (-1250 3275);
DISPLAY INVISIBLE (-1250 3275);
FORCEPROP 1 LASTPIN (-1300 3250) $PN 1
J 0
(-1290 3235);
DISPLAY 0.489362 (-1290 3235);
PAINT MONO (-1290 3235);
FORCEPROP 1 LASTPIN (-1300 3050) $PN 2
J 0
(-1290 3035);
DISPLAY 0.489362 (-1290 3035);
PAINT MONO (-1290 3035);
FORCEPROP 1 LAST PACK_TYPE SMLF
J 0
(-1250 3000);
DISPLAY 0.489362 (-1250 3000);
PAINT SKYBLUE (-1250 3000);
FORCEPROP 1 LAST VOLTAGE 2.5V
J 0
(-1250 3100);
DISPLAY 0.489362 (-1250 3100);
PAINT SKYBLUE (-1250 3100);
FORCEPROP 1 LAST VALUE 390UF
J 0
(-1250 3200);
DISPLAY 0.489362 (-1250 3200);
PAINT SKYBLUE (-1250 3200);
FORCEPROP 1 LAST MATERIAL ALUM
J 0
(-1250 3050);
DISPLAY 0.489362 (-1250 3050);
PAINT SKYBLUE (-1250 3050);
FORCEPROP 1 LAST TOLERANCE 20%
J 0
(-1250 3150);
DISPLAY 0.489362 (-1250 3150);
PAINT SKYBLUE (-1250 3150);
FORCEPROP 2 LAST CDS_LIB pure_quanta
J 0
(-1300 3150);
DISPLAY INVISIBLE (-1300 3150);
FORCEPROP 1 LAST PATH I46
J 0
(-1250 3300);
DISPLAY 0.978723 (-1250 3300);
DISPLAY INVISIBLE (-1250 3300);
FORCEPROP 1 LAST PART_NUMBER CC7390JMZ13
J 0
(-1250 2950);
DISPLAY 0.489362 (-1250 2950);
PAINT SKYBLUE (-1250 2950);
DISPLAY INVISIBLE (-1250 2950);
FORCEADD UNIVERSAL_GND..1
(-975 2775);
FORCEPROP 3 LASTPIN (-975 2825) SIG_NAME GND\g
J 0
(-965 2835);
DISPLAY 0.659574 (-965 2835);
PAINT MONO (-965 2835);
DISPLAY INVISIBLE (-965 2835);
FORCEPROP 2 LAST CDS_LIB pure_quanta_power
J 0
(-975 2775);
DISPLAY INVISIBLE (-975 2775);
FORCEPROP 1 LAST HDL_POWER GND
J 1
(-950 2700);
DISPLAY 0.872340 (-950 2700);
PAINT GREEN (-950 2700);
DISPLAY INVISIBLE (-950 2700);
FORCEPROP 1 LAST PATH I47
J 0
(-900 2775);
DISPLAY 0.872340 (-900 2775);
PAINT AQUA (-900 2775);
DISPLAY INVISIBLE (-900 2775);
FORCEADD Q_CAPP..1
(-1000 3150);
FORCEPROP 1 LAST LOCATION PC6805
J 0
(-950 3250);
DISPLAY 0.489362 (-950 3250);
PAINT SKYBLUE (-950 3250);
FORCEPROP 0 LAST $SEC 1
J 0
(-950 3275);
DISPLAY 0.680851 (-950 3275);
PAINT MONO (-950 3275);
DISPLAY INVISIBLE (-950 3275);
FORCEPROP 0 LAST CDS_SEC 1
J 0
(-950 3275);
DISPLAY 0.680851 (-950 3275);
DISPLAY INVISIBLE (-950 3275);
FORCEPROP 1 LASTPIN (-1000 3250) $PN 1
J 0
(-990 3235);
DISPLAY 0.787234 (-990 3235);
PAINT MONO (-990 3235);
FORCEPROP 1 LASTPIN (-1000 3050) $PN 2
J 0
(-990 3035);
DISPLAY 0.787234 (-990 3035);
PAINT MONO (-990 3035);
FORCEPROP 1 LAST PACK_TYPE SMLF
J 0
(-950 3000);
DISPLAY 0.489362 (-950 3000);
PAINT SKYBLUE (-950 3000);
FORCEPROP 1 LAST VALUE 390UF
J 0
(-950 3200);
DISPLAY 0.489362 (-950 3200);
PAINT SKYBLUE (-950 3200);
FORCEPROP 1 LAST TOLERANCE 20%
J 0
(-950 3150);
DISPLAY 0.489362 (-950 3150);
PAINT SKYBLUE (-950 3150);
FORCEPROP 1 LAST MATERIAL ALUM
J 0
(-950 3050);
DISPLAY 0.489362 (-950 3050);
PAINT SKYBLUE (-950 3050);
FORCEPROP 1 LAST VOLTAGE 2.5V
J 0
(-950 3100);
DISPLAY 0.489362 (-950 3100);
PAINT SKYBLUE (-950 3100);
FORCEPROP 2 LAST CDS_LIB pure_quanta
J 0
(-1000 3150);
DISPLAY INVISIBLE (-1000 3150);
FORCEPROP 1 LAST PATH I48
J 0
(-950 3300);
DISPLAY 0.978723 (-950 3300);
DISPLAY INVISIBLE (-950 3300);
FORCEPROP 1 LAST PART_NUMBER CC7390JMZ13
J 0
(-950 2950);
DISPLAY 0.489362 (-950 2950);
PAINT SKYBLUE (-950 2950);
DISPLAY INVISIBLE (-950 2950);
FORCEADD Q_CAP..1
(-675 3150);
FORCEPROP 1 LAST LOCATION PC6514
J 0
(-625 3250);
DISPLAY 0.489362 (-625 3250);
PAINT SKYBLUE (-625 3250);
FORCEPROP 2 LAST SEC 1
J 0
(-623 3357);
DISPLAY 0.680851 (-623 3357);
PAINT MONO (-623 3357);
DISPLAY INVISIBLE (-623 3357);
FORCEPROP 1 LASTPIN (-675 3250) $PN 1
J 0
(-665 3230);
DISPLAY 0.489362 (-665 3230);
FORCEPROP 1 LASTPIN (-675 3050) $PN 2
J 0
(-665 3030);
DISPLAY 0.489362 (-665 3030);
FORCEPROP 1 LAST VOLTAGE 25V
J 0
(-625 3150);
DISPLAY 0.489362 (-625 3150);
PAINT SKYBLUE (-625 3150);
FORCEPROP 1 LAST TOLERANCE 10%
J 0
(-625 3100);
DISPLAY 0.489362 (-625 3100);
PAINT SKYBLUE (-625 3100);
FORCEPROP 1 LAST VALUE 0.1UF
J 0
(-625 3200);
DISPLAY 0.489362 (-625 3200);
PAINT SKYBLUE (-625 3200);
FORCEPROP 1 LAST PACK_TYPE 0402
J 0
(-625 2950);
DISPLAY 0.489362 (-625 2950);
PAINT SKYBLUE (-625 2950);
FORCEPROP 1 LAST MATERIAL X7R
J 0
(-625 3050);
DISPLAY 0.489362 (-625 3050);
PAINT SKYBLUE (-625 3050);
FORCEPROP 2 LAST SEC_TYPE 0402
J 0
(-625 3346);
DISPLAY 1.021277 (-625 3346);
DISPLAY INVISIBLE (-625 3346);
FORCEPROP 2 LAST CDS_LIB pure_quanta
J 0
(-675 3150);
PAINT MONO (-675 3150);
DISPLAY INVISIBLE (-675 3150);
FORCEPROP 1 LAST PATH I49
J 0
(-625 3300);
DISPLAY 0.978723 (-625 3300);
PAINT WHITE (-625 3300);
DISPLAY INVISIBLE (-625 3300);
FORCEPROP 1 LAST PART_NUMBER CH4104K1B00
J 0
(-625 3000);
DISPLAY 0.489362 (-625 3000);
PAINT SKYBLUE (-625 3000);
DISPLAY INVISIBLE (-625 3000);
FORCEADD Q_CAP..1
R 2
(-8450 3200);
FORCEPROP 1 LAST LOCATION C6757
J 2
(-8500 3300);
DISPLAY 0.489362 (-8500 3300);
PAINT SKYBLUE (-8500 3300);
FORCEPROP 0 LAST $SEC 1
J 0
(-8500 3350);
DISPLAY 0.680851 (-8500 3350);
PAINT MONO (-8500 3350);
DISPLAY INVISIBLE (-8500 3350);
FORCEPROP 0 LAST CDS_SEC 1
J 0
(-8500 3350);
DISPLAY 0.680851 (-8500 3350);
DISPLAY INVISIBLE (-8500 3350);
FORCEPROP 1 LASTPIN (-8450 3300) $PN 1
J 2
(-8460 3280);
DISPLAY 0.489362 (-8460 3280);
PAINT MONO (-8460 3280);
FORCEPROP 1 LASTPIN (-8450 3100) $PN 2
J 2
(-8460 3080);
DISPLAY 0.489362 (-8460 3080);
PAINT MONO (-8460 3080);
FORCEPROP 1 LAST VALUE 0.1UF
J 2
(-8500 3250);
DISPLAY 0.489362 (-8500 3250);
PAINT SKYBLUE (-8500 3250);
FORCEPROP 1 LAST MATERIAL EMPTY
J 2
(-8500 3100);
DISPLAY 0.489362 (-8500 3100);
PAINT RED (-8500 3100);
FORCEPROP 1 LAST VOLTAGE 25V
J 2
(-8500 3200);
DISPLAY 0.489362 (-8500 3200);
PAINT SKYBLUE (-8500 3200);
FORCEPROP 1 LAST TOLERANCE 10%
J 2
(-8500 3150);
DISPLAY 0.489362 (-8500 3150);
PAINT SKYBLUE (-8500 3150);
FORCEPROP 1 LAST PACK_TYPE 0402
J 2
(-8500 3000);
DISPLAY 0.489362 (-8500 3000);
PAINT SKYBLUE (-8500 3000);
FORCEPROP 2 LAST CDS_LIB pure_quanta
J 0
(-8450 3200);
DISPLAY INVISIBLE (-8450 3200);
FORCEPROP 1 LAST PATH I5
J 2
(-8500 3350);
DISPLAY 0.978723 (-8500 3350);
PAINT WHITE (-8500 3350);
DISPLAY INVISIBLE (-8500 3350);
FORCEPROP 1 LAST PART_NUMBER CH4104K1B00
J 2
(-8525 3050);
DISPLAY 0.489362 (-8525 3050);
PAINT SKYBLUE (-8525 3050);
DISPLAY INVISIBLE (-8525 3050);
FORCEADD P1V0..1
(-375 3775);
FORCEPROP 3 LASTPIN (-375 3725) SIG_NAME P1V8_CPU0_RT_1D\g
J 0
(-365 3735);
DISPLAY 0.659574 (-365 3735);
PAINT MONO (-365 3735);
DISPLAY INVISIBLE (-365 3735);
FORCEPROP 1 LAST HDL_POWER P1V8_CPU0_RT_1D
J 1
(-375 3825);
DISPLAY 0.489362 (-375 3825);
PAINT GREEN (-375 3825);
FORCEPROP 2 LAST CDS_LIB pure_quanta_power
J 0
(-375 3775);
PAINT MONO (-375 3775);
DISPLAY INVISIBLE (-375 3775);
FORCEPROP 1 LAST PATH I50
J 0
(-325 3800);
DISPLAY 0.872340 (-325 3800);
PAINT AQUA (-325 3800);
DISPLAY INVISIBLE (-325 3800);
FORCEADD MPQ8633BGLEC838Z..1
(-5625 3225);
FORCEPROP 1 LAST LOCATION PU6500
J 0
(-5872 4132);
DISPLAY 0.489362 (-5872 4132);
PAINT SKYBLUE (-5872 4132);
FORCEPROP 0 LAST $SEC 1
J 0
(-5875 4300);
DISPLAY 0.680851 (-5875 4300);
PAINT MONO (-5875 4300);
DISPLAY INVISIBLE (-5875 4300);
FORCEPROP 0 LAST CDS_SEC 1
J 0
(-5875 4300);
DISPLAY 1.021277 (-5875 4300);
DISPLAY INVISIBLE (-5875 4300);
FORCEPROP 0 LASTPIN (-5225 2550) $PN 2
J 0
(-5215 2560);
DISPLAY 0.489362 (-5215 2560);
PAINT MONO (-5215 2560);
FORCEPROP 0 LASTPIN (-5225 3700) $PN 1
J 0
(-5215 3710);
DISPLAY 0.489362 (-5215 3710);
PAINT MONO (-5215 3710);
FORCEPROP 0 LASTPIN (-6025 2600) $PN 3
J 2
(-6035 2610);
DISPLAY 0.489362 (-6035 2610);
PAINT MONO (-6035 2610);
FORCEPROP 0 LASTPIN (-6025 3400) $PN 8
J 2
(-6035 3410);
DISPLAY 0.489362 (-6035 3410);
PAINT MONO (-6035 3410);
FORCEPROP 0 LASTPIN (-5225 2950) $PN 7
J 0
(-5215 2960);
DISPLAY 0.489362 (-5215 2960);
PAINT MONO (-5215 2960);
FORCEPROP 0 LASTPIN (-6025 3200) $PN 4
J 2
(-6035 3210);
DISPLAY 0.489362 (-6035 3210);
PAINT MONO (-6035 3210);
FORCEPROP 0 LASTPIN (-5225 2600) $PN 11_18
J 0
(-5215 2610);
DISPLAY 0.489362 (-5215 2610);
PAINT MONO (-5215 2610);
FORCEPROP 0 LASTPIN (-5225 3900) $PN 9
J 0
(-5215 3910);
DISPLAY 0.489362 (-5215 3910);
PAINT MONO (-5215 3910);
FORCEPROP 0 LASTPIN (-5225 2800) $PN 6
J 0
(-5215 2810);
DISPLAY 0.489362 (-5215 2810);
PAINT MONO (-5215 2810);
FORCEPROP 0 LASTPIN (-5225 3400) $PN 20
J 0
(-5215 3410);
DISPLAY 0.489362 (-5215 3410);
PAINT MONO (-5215 3410);
FORCEPROP 0 LASTPIN (-5225 2700) $PN 5
J 0
(-5215 2710);
DISPLAY 0.489362 (-5215 2710);
PAINT MONO (-5215 2710);
FORCEPROP 0 LASTPIN (-6025 2950) $PN 19
J 2
(-6035 2960);
DISPLAY 0.489362 (-6035 2960);
PAINT MONO (-6035 2960);
FORCEPROP 0 LASTPIN (-6025 3900) $PN 10
J 2
(-6035 3910);
DISPLAY 0.489362 (-6035 3910);
PAINT MONO (-6035 3910);
FORCEPROP 0 LASTPIN (-6025 3850) $PN 21
J 2
(-6035 3860);
DISPLAY 0.489362 (-6035 3860);
PAINT MONO (-6035 3860);
FORCEPROP 1 LAST MATERIAL IC
J 0
(-5872 3954);
DISPLAY 0.489362 (-5872 3954);
PAINT SKYBLUE (-5872 3954);
FORCEPROP 2 LAST VALUE MPQ8633BGLE-C838-Z
J 0
(-5875 4200);
DISPLAY 0.489362 (-5875 4200);
PAINT SKYBLUE (-5875 4200);
FORCEPROP 2 LAST PART_TYPE SMLF
J 0
(-5875 4250);
DISPLAY 0.680851 (-5875 4250);
FORCEPROP 2 LAST CDS_LIB pure_quanta
J 0
(-5625 3225);
DISPLAY INVISIBLE (-5625 3225);
FORCEPROP 1 LAST NEEDS_NO_SIZE TRUE
J 0
(-5625 3225);
DISPLAY 0.723404 (-5625 3225);
PAINT GREEN (-5625 3225);
DISPLAY INVISIBLE (-5625 3225);
FORCEPROP 1 LAST CDS_LMAN_SYM_OUTLINE -250,725,250,-725
J 0
(-5625 3225);
DISPLAY 0.468085 (-5625 3225);
PAINT GREEN (-5625 3225);
DISPLAY INVISIBLE (-5625 3225);
FORCEPROP 1 LAST PATH I51
J 0
(-5625 3225);
DISPLAY 0.723404 (-5625 3225);
PAINT GREEN (-5625 3225);
DISPLAY INVISIBLE (-5625 3225);
FORCEPROP 1 LAST PART_NUMBER AL008633005
J 0
(-5872 4033);
DISPLAY 0.489362 (-5872 4033);
PAINT SKYBLUE (-5872 4033);
DISPLAY INVISIBLE (-5872 4033);
FORCEADD Q_CAP..1
(-1575 3150);
FORCEPROP 1 LAST LOCATION PC6512
J 0
(-1525 3250);
DISPLAY 0.489362 (-1525 3250);
PAINT SKYBLUE (-1525 3250);
FORCEPROP 0 LAST $SEC 1
J 0
(-1525 3275);
DISPLAY 0.680851 (-1525 3275);
PAINT MONO (-1525 3275);
DISPLAY INVISIBLE (-1525 3275);
FORCEPROP 0 LAST CDS_SEC 1
J 0
(-1525 3275);
DISPLAY 0.680851 (-1525 3275);
DISPLAY INVISIBLE (-1525 3275);
FORCEPROP 1 LASTPIN (-1575 3250) $PN 1
J 0
(-1565 3230);
DISPLAY 0.787234 (-1565 3230);
PAINT MONO (-1565 3230);
FORCEPROP 1 LASTPIN (-1575 3050) $PN 2
J 0
(-1565 3030);
DISPLAY 0.787234 (-1565 3030);
PAINT MONO (-1565 3030);
FORCEPROP 1 LAST VALUE 22UF
J 0
(-1525 3200);
DISPLAY 0.489362 (-1525 3200);
PAINT SKYBLUE (-1525 3200);
FORCEPROP 1 LAST VOLTAGE 4V
J 0
(-1525 3150);
DISPLAY 0.489362 (-1525 3150);
PAINT SKYBLUE (-1525 3150);
FORCEPROP 1 LAST PACK_TYPE C0805
J 0
(-1525 3000);
DISPLAY 0.489362 (-1525 3000);
PAINT SKYBLUE (-1525 3000);
FORCEPROP 1 LAST MATERIAL X6S
J 0
(-1525 3050);
DISPLAY 0.489362 (-1525 3050);
PAINT RED (-1525 3050);
FORCEPROP 1 LAST TOLERANCE 20%
J 0
(-1525 3100);
DISPLAY 0.489362 (-1525 3100);
PAINT SKYBLUE (-1525 3100);
FORCEPROP 2 LAST CDS_LIB pure_quanta
J 0
(-1575 3150);
DISPLAY INVISIBLE (-1575 3150);
FORCEPROP 1 LAST PATH I52
J 0
(-1525 3300);
DISPLAY 0.978723 (-1525 3300);
PAINT WHITE (-1525 3300);
DISPLAY INVISIBLE (-1525 3300);
FORCEPROP 1 LAST PART_NUMBER CH622KMEA03
J 0
(-1525 3000);
DISPLAY 0.489362 (-1525 3000);
PAINT SKYBLUE (-1525 3000);
DISPLAY INVISIBLE (-1525 3000);
FORCEADD Q_CAP..1
(-6450 3975);
FORCEPROP 1 LAST LOCATION PC6902
J 0
(-6400 4075);
DISPLAY 0.510638 (-6400 4075);
FORCEPROP 0 LAST $SEC 1
J 0
(-6400 4100);
DISPLAY 0.680851 (-6400 4100);
PAINT MONO (-6400 4100);
DISPLAY INVISIBLE (-6400 4100);
FORCEPROP 0 LAST CDS_SEC 1
J 0
(-6400 4100);
DISPLAY 0.680851 (-6400 4100);
DISPLAY INVISIBLE (-6400 4100);
FORCEPROP 1 LASTPIN (-6450 4075) $PN 1
J 0
(-6440 4055);
DISPLAY 0.787234 (-6440 4055);
PAINT MONO (-6440 4055);
FORCEPROP 1 LASTPIN (-6450 3875) $PN 2
J 0
(-6440 3855);
DISPLAY 0.787234 (-6440 3855);
PAINT MONO (-6440 3855);
FORCEPROP 1 LAST TOLERANCE 20%
J 0
(-6400 3925);
DISPLAY 0.510638 (-6400 3925);
FORCEPROP 1 LAST PACK_TYPE C0805
J 0
(-6400 3775);
DISPLAY 0.510638 (-6400 3775);
FORCEPROP 1 LAST MATERIAL X6S
J 0
(-6400 3875);
DISPLAY 0.510638 (-6400 3875);
FORCEPROP 1 LAST VOLTAGE 16V
J 0
(-6400 3975);
DISPLAY 0.510638 (-6400 3975);
FORCEPROP 1 LAST VALUE 22UF
J 0
(-6400 4025);
DISPLAY 0.510638 (-6400 4025);
FORCEPROP 2 LAST CDS_LIB pure_quanta
J 0
(-6450 3975);
DISPLAY INVISIBLE (-6450 3975);
FORCEPROP 1 LAST PATH I56
J 0
(-6400 4125);
DISPLAY 0.978723 (-6400 4125);
PAINT WHITE (-6400 4125);
DISPLAY INVISIBLE (-6400 4125);
FORCEPROP 1 LAST PART_NUMBER CH6223MEA01
J 0
(-6400 3825);
DISPLAY 0.404255 (-6400 3825);
DISPLAY INVISIBLE (-6400 3825);
FORCEADD Q_CAP..1
(-6650 3975);
FORCEPROP 1 LAST LOCATION PC6901
J 0
(-6600 4075);
DISPLAY 0.510638 (-6600 4075);
FORCEPROP 0 LAST $SEC 1
J 0
(-6600 4100);
DISPLAY 0.680851 (-6600 4100);
PAINT MONO (-6600 4100);
DISPLAY INVISIBLE (-6600 4100);
FORCEPROP 0 LAST CDS_SEC 1
J 0
(-6600 4100);
DISPLAY 0.680851 (-6600 4100);
DISPLAY INVISIBLE (-6600 4100);
FORCEPROP 1 LASTPIN (-6650 4075) $PN 1
J 0
(-6640 4055);
DISPLAY 0.787234 (-6640 4055);
PAINT MONO (-6640 4055);
FORCEPROP 1 LASTPIN (-6650 3875) $PN 2
J 0
(-6640 3855);
DISPLAY 0.787234 (-6640 3855);
PAINT MONO (-6640 3855);
FORCEPROP 1 LAST PACK_TYPE C0805
J 0
(-6600 3775);
DISPLAY 0.510638 (-6600 3775);
FORCEPROP 1 LAST MATERIAL X6S
J 0
(-6600 3875);
DISPLAY 0.510638 (-6600 3875);
FORCEPROP 1 LAST TOLERANCE 20%
J 0
(-6600 3925);
DISPLAY 0.510638 (-6600 3925);
FORCEPROP 1 LAST VOLTAGE 16V
J 0
(-6600 3975);
DISPLAY 0.510638 (-6600 3975);
FORCEPROP 1 LAST VALUE 22UF
J 0
(-6600 4025);
DISPLAY 0.510638 (-6600 4025);
FORCEPROP 2 LAST CDS_LIB pure_quanta
J 0
(-6650 3975);
DISPLAY INVISIBLE (-6650 3975);
FORCEPROP 1 LAST PATH I57
J 0
(-6600 4125);
DISPLAY 0.978723 (-6600 4125);
PAINT WHITE (-6600 4125);
DISPLAY INVISIBLE (-6600 4125);
FORCEPROP 1 LAST PART_NUMBER CH6223MEA01
J 0
(-6600 3825);
DISPLAY 0.404255 (-6600 3825);
DISPLAY INVISIBLE (-6600 3825);
FORCEADD Q_CAP..1
(-6850 3975);
FORCEPROP 1 LAST LOCATION PC6900
J 0
(-6800 4075);
DISPLAY 0.510638 (-6800 4075);
FORCEPROP 0 LAST $SEC 1
J 0
(-6800 4100);
DISPLAY 0.680851 (-6800 4100);
PAINT MONO (-6800 4100);
DISPLAY INVISIBLE (-6800 4100);
FORCEPROP 0 LAST CDS_SEC 1
J 0
(-6800 4100);
DISPLAY 0.680851 (-6800 4100);
DISPLAY INVISIBLE (-6800 4100);
FORCEPROP 1 LASTPIN (-6850 4075) $PN 1
J 0
(-6840 4055);
DISPLAY 0.787234 (-6840 4055);
PAINT MONO (-6840 4055);
FORCEPROP 1 LASTPIN (-6850 3875) $PN 2
J 0
(-6840 3855);
DISPLAY 0.787234 (-6840 3855);
PAINT MONO (-6840 3855);
FORCEPROP 1 LAST PACK_TYPE C0805
J 0
(-6800 3775);
DISPLAY 0.510638 (-6800 3775);
FORCEPROP 1 LAST MATERIAL X6S
J 0
(-6800 3875);
DISPLAY 0.510638 (-6800 3875);
FORCEPROP 1 LAST TOLERANCE 20%
J 0
(-6800 3925);
DISPLAY 0.510638 (-6800 3925);
FORCEPROP 1 LAST VOLTAGE 16V
J 0
(-6800 3975);
DISPLAY 0.510638 (-6800 3975);
FORCEPROP 1 LAST VALUE 22UF
J 0
(-6800 4025);
DISPLAY 0.510638 (-6800 4025);
FORCEPROP 2 LAST CDS_LIB pure_quanta
J 0
(-6850 3975);
DISPLAY INVISIBLE (-6850 3975);
FORCEPROP 1 LAST PATH I58
J 0
(-6800 4125);
DISPLAY 0.978723 (-6800 4125);
PAINT WHITE (-6800 4125);
DISPLAY INVISIBLE (-6800 4125);
FORCEPROP 1 LAST PART_NUMBER CH6223MEA01
J 0
(-6800 3825);
DISPLAY 0.404255 (-6800 3825);
DISPLAY INVISIBLE (-6800 3825);
FORCEADD Q_CAPP..1
R 2
(-8450 3975);
FORCEPROP 1 LAST LOCATION PC6800
J 2
(-8500 4075);
DISPLAY 0.787234 (-8500 4075);
FORCEPROP 0 LAST $SEC 1
J 2
(-8500 4125);
DISPLAY 0.680851 (-8500 4125);
PAINT MONO (-8500 4125);
DISPLAY INVISIBLE (-8500 4125);
FORCEPROP 0 LAST CDS_SEC 1
J 2
(-8500 4125);
DISPLAY 0.680851 (-8500 4125);
DISPLAY INVISIBLE (-8500 4125);
FORCEPROP 1 LASTPIN (-8450 4075) $PN 1
J 2
(-8460 4060);
DISPLAY 0.787234 (-8460 4060);
PAINT MONO (-8460 4060);
FORCEPROP 1 LASTPIN (-8450 3875) $PN 2
J 2
(-8460 3860);
DISPLAY 0.787234 (-8460 3860);
PAINT MONO (-8460 3860);
FORCEPROP 1 LAST TOLERANCE 20%
J 2
(-8500 3975);
DISPLAY 0.510638 (-8500 3975);
FORCEPROP 1 LAST VALUE 270UF
J 2
(-8500 4025);
DISPLAY 0.510638 (-8500 4025);
FORCEPROP 1 LAST PACK_TYPE SMLF
J 2
(-8500 3825);
DISPLAY 0.510638 (-8500 3825);
FORCEPROP 1 LAST MATERIAL OSCON
J 2
(-8500 3875);
DISPLAY 0.510638 (-8500 3875);
FORCEPROP 1 LAST VOLTAGE 16V
J 2
(-8500 3925);
DISPLAY 0.510638 (-8500 3925);
FORCEPROP 2 LAST CDS_LIB pure_quanta
J 2
(-8450 3975);
DISPLAY INVISIBLE (-8450 3975);
FORCEPROP 1 LAST PATH I6
J 2
(-8500 4125);
DISPLAY 0.978723 (-8500 4125);
DISPLAY INVISIBLE (-8500 4125);
FORCEPROP 1 LAST PART_NUMBER CC72703MZ11
J 2
(-8500 3775);
DISPLAY 0.510638 (-8500 3775);
DISPLAY INVISIBLE (-8500 3775);
FORCEADD Q_CAP..1
(-8300 3975);
FORCEPROP 1 LAST LOCATION PC6802
J 0
(-8250 4075);
DISPLAY 0.489362 (-8250 4075);
PAINT SKYBLUE (-8250 4075);
FORCEPROP 0 LAST $SEC 1
J 0
(-8250 4100);
DISPLAY 0.680851 (-8250 4100);
PAINT MONO (-8250 4100);
DISPLAY INVISIBLE (-8250 4100);
FORCEPROP 0 LAST CDS_SEC 1
J 0
(-8250 4100);
DISPLAY 0.680851 (-8250 4100);
DISPLAY INVISIBLE (-8250 4100);
FORCEPROP 1 LASTPIN (-8300 4075) $PN 1
J 0
(-8290 4055);
DISPLAY 0.787234 (-8290 4055);
PAINT MONO (-8290 4055);
FORCEPROP 1 LASTPIN (-8300 3875) $PN 2
J 0
(-8290 3855);
DISPLAY 0.787234 (-8290 3855);
PAINT MONO (-8290 3855);
FORCEPROP 1 LAST MATERIAL X6S
J 0
(-8250 3875);
DISPLAY 0.489362 (-8250 3875);
PAINT SKYBLUE (-8250 3875);
FORCEPROP 1 LAST VOLTAGE 16V
J 0
(-8250 3975);
DISPLAY 0.489362 (-8250 3975);
PAINT SKYBLUE (-8250 3975);
FORCEPROP 1 LAST VALUE 22UF
J 0
(-8250 4025);
DISPLAY 0.489362 (-8250 4025);
PAINT SKYBLUE (-8250 4025);
FORCEPROP 1 LAST TOLERANCE 20%
J 0
(-8250 3925);
DISPLAY 0.489362 (-8250 3925);
PAINT SKYBLUE (-8250 3925);
FORCEPROP 1 LAST PACK_TYPE C0805
J 0
(-8250 3775);
DISPLAY 0.489362 (-8250 3775);
PAINT SKYBLUE (-8250 3775);
FORCEPROP 2 LAST CDS_LIB pure_quanta
J 0
(-8300 3975);
DISPLAY INVISIBLE (-8300 3975);
FORCEPROP 1 LAST PATH I7
J 0
(-8250 4125);
DISPLAY 0.978723 (-8250 4125);
PAINT WHITE (-8250 4125);
DISPLAY INVISIBLE (-8250 4125);
FORCEPROP 1 LAST PART_NUMBER CH6223MEA01
J 0
(-8250 3825);
DISPLAY 0.489362 (-8250 3825);
PAINT SKYBLUE (-8250 3825);
DISPLAY INVISIBLE (-8250 3825);
FORCEADD P1V0_AUX..1
(-9100 4375);
FORCEPROP 3 LASTPIN (-9100 4325) SIG_NAME P12V_AUX\g
J 0
(-9090 4335);
DISPLAY 0.659574 (-9090 4335);
PAINT MONO (-9090 4335);
DISPLAY INVISIBLE (-9090 4335);
FORCEPROP 1 LAST HDL_POWER P12V_AUX
J 1
(-9089 4422);
DISPLAY 0.489362 (-9089 4422);
PAINT GREEN (-9089 4422);
FORCEPROP 2 LAST ROOM VR_DDR1_POWER_STAGE
J 0
(-9100 4475);
DISPLAY 0.978723 (-9100 4475);
PAINT RED (-9100 4475);
DISPLAY INVISIBLE (-9100 4475);
FORCEPROP 1 LAST VOLTAGE 1.0V
J 0
(-9145 4332);
DISPLAY 0.340426 (-9145 4332);
PAINT SKYBLUE (-9145 4332);
DISPLAY INVISIBLE (-9145 4332);
FORCEPROP 2 LAST CDS_LIB mstr_symbols
J 0
(-9100 4375);
DISPLAY INVISIBLE (-9100 4375);
FORCEPROP 1 LAST BODY_TYPE PLUMBING
J 0
(-9145 4332);
DISPLAY 0.340426 (-9145 4332);
PAINT GREEN (-9145 4332);
DISPLAY INVISIBLE (-9145 4332);
FORCEPROP 1 LAST PATH I8
J 0
(-9050 4400);
DISPLAY 0.872340 (-9050 4400);
PAINT AQUA (-9050 4400);
DISPLAY INVISIBLE (-9050 4400);
FORCEADD Q_INDUCTOR..1
(-8750 4200);
FORCEPROP 1 LAST LOCATION PL6500
J 0
(-8875 4360);
DISPLAY 0.489362 (-8875 4360);
PAINT SKYBLUE (-8875 4360);
FORCEPROP 0 LAST $SEC 1
J 0
(-8875 4475);
DISPLAY 0.680851 (-8875 4475);
PAINT MONO (-8875 4475);
DISPLAY INVISIBLE (-8875 4475);
FORCEPROP 0 LAST CDS_SEC 1
J 0
(-8875 4475);
DISPLAY 0.680851 (-8875 4475);
DISPLAY INVISIBLE (-8875 4475);
FORCEPROP 0 LASTPIN (-8850 4175) $PN 1
J 2
(-8860 4185);
DISPLAY 0.680851 (-8860 4185);
PAINT MONO (-8860 4185);
FORCEPROP 0 LASTPIN (-8650 4175) $PN 2
J 0
(-8640 4185);
DISPLAY 0.680851 (-8640 4185);
PAINT MONO (-8640 4185);
FORCEPROP 2 LAST VALUE 100NH/16A
J 0
(-8875 4450);
DISPLAY 0.489362 (-8875 4450);
PAINT SKYBLUE (-8875 4450);
FORCEPROP 2 LAST PACK_TYPE SMLF
J 0
(-8875 4400);
DISPLAY 0.489362 (-8875 4400);
PAINT SKYBLUE (-8875 4400);
FORCEPROP 1 LAST MATERIAL IND
J 0
(-8875 4255);
DISPLAY 0.489362 (-8875 4255);
PAINT SKYBLUE (-8875 4255);
FORCEPROP 2 LAST CDS_LIB pure_quanta
J 0
(-8750 4200);
DISPLAY INVISIBLE (-8750 4200);
FORCEPROP 1 LAST NEEDS_NO_SIZE TRUE
J 0
(-8750 4200);
DISPLAY 0.468085 (-8750 4200);
PAINT GREEN (-8750 4200);
DISPLAY INVISIBLE (-8750 4200);
FORCEPROP 1 LAST PATH I9
J 0
(-8675 4255);
DISPLAY 0.723404 (-8675 4255);
PAINT GREEN (-8675 4255);
DISPLAY INVISIBLE (-8675 4255);
FORCEPROP 1 LAST PART_NUMBER CV+10G0MZ04
J 0
(-8875 4310);
DISPLAY 0.489362 (-8875 4310);
PAINT SKYBLUE (-8875 4310);
DISPLAY INVISIBLE (-8875 4310);
FORCEADD QUANTA_TITLE_BLOCK_C..1
(0 0);
FORCEPROP 0 LAST CDS_CON_LAST_MODIFIED Thu Sep 14 16:13:01 2023
J 0
(-1885 15);
DISPLAY INVISIBLE (-1885 15);
FORCEPROP 1 LAST CUSTOM_TXT_CDS <CON_LAST_MODIFIED>
J 0
(-1885 15);
DISPLAY 0.978723 (-1885 15);
FORCEPROP 2 LAST CUSTOM_TXT_CDS <XR_PAGE_TITLE>
J 0
(-7890 5250);
DISPLAY 0.638298 (-7890 5250);
PAINT PINK (-7890 5250);
DISPLAY INVISIBLE (-7890 5250);
FORCEPROP 1 LAST CUSTOM_TXT_CDS <NAME_2>
J 0
(-3175 50);
FORCEPROP 1 LAST CUSTOM_TXT_CDS <NAME_1>
J 0
(-3175 175);
FORCEPROP 1 LAST CUSTOM_TXT_CDS <Q_NUMBER>
J 0
(-1403 103);
DISPLAY 1.212766 (-1403 103);
FORCEPROP 1 LAST CUSTOM_TXT_CDS <Q_PROJ>
J 0
(-2382 102);
DISPLAY 1.212766 (-2382 102);
FORCEPROP 1 LAST CUSTOM_TXT_CDS <Q_REV>
J 0
(-184 103);
DISPLAY 1.212766 (-184 103);
FORCEPROP 1 LAST CUSTOM_TXT_CDS <CON_PAGE_NUM> OF <CON_TOTAL_PAGES>
J 0
(-446 18);
DISPLAY 0.978723 (-446 18);
FORCEPROP 1 LAST Q_TITLE P1V8_CPU0_RT_1D
J 0
(-9366 26);
DISPLAY 2.446809 (-9366 26);
PAINT GREEN (-9366 26);
FORCEPROP 2 LAST CDS_XR_PAGE_TITLE CR-361 : @T6G_MB_LIB.T6G(SCH_1):PAGE361
J 0
(-7890 5250);
DISPLAY 0.638298 (-7890 5250);
PAINT PINK (-7890 5250);
DISPLAY INVISIBLE (-7890 5250);
FORCEPROP 2 LAST PAGE_BORDER TRUE
J 0
(-7890 5250);
DISPLAY 0.638298 (-7890 5250);
PAINT PINK (-7890 5250);
DISPLAY INVISIBLE (-7890 5250);
FORCEPROP 1 LAST CDS_LMAN_SYM_OUTLINE -9475,6775,100,-125
J 0
(0 0);
DISPLAY 0.468085 (0 0);
PAINT GREEN (0 0);
DISPLAY INVISIBLE (0 0);
FORCEPROP 2 LAST CDS_LIB pure_quanta
J 0
(0 0);
DISPLAY INVISIBLE (0 0);
FORCEPROP 1 LAST Q_DEPT BU9
J 1
(-3763 49);
DISPLAY 1.957447 (-3763 49);
PAINT GREEN (-3763 49);
DISPLAY INVISIBLE (-3763 49);
FORCEPROP 1 LAST COMMENT_BODY TRUE
J 0
(12 -13);
DISPLAY 0.978723 (12 -13);
PAINT GREEN (12 -13);
DISPLAY INVISIBLE (12 -13);
FORCEADD DNS..1
(-8475 3100);
PAINT RED (-8475 3100);
FORCEPROP 2 LAST CDS_LIB mstr_misc
J 0
(-8475 3100);
DISPLAY INVISIBLE (-8475 3100);
FORCEPROP 1 LAST COMMENT_BODY TRUE
J 0
(-8475 3100);
DISPLAY INVISIBLE (-8475 3100);
WIRE 16 -1 (-8450 3050)(-8450 3100);
WIRE 16 -1 (-7925 3200)(-7050 3200);
WIRE 16 -1 (-7925 3200)(-7925 2800);
WIRE 16 -1 (-7450 2200)(-7450 2275);
WIRE 16 -1 (-7450 2950)(-7450 2900);
WIRE 16 -1 (-6575 2275)(-6575 2175);
WIRE 16 -1 (-4875 2325)(-4875 2425);
WIRE 16 -1 (-5225 2800)(-4425 2800);
WIRE 16 -1 (-4425 2800)(-4425 2300);
WIRE 16 -1 (-9100 3875)(-9100 3700);
WIRE 16 -1 (-4575 4425)(-4575 4300);
WIRE 16 -1 (-4025 2325)(-4025 2225);
WIRE 16 -1 (-2725 3650)(-2725 3600);
WIRE 17 273 (-9050 1200)(-6875 1200);
WIRE 17 273 (-9050 1675)(-9050 1200);
WIRE 17 273 (-6875 1675)(-6875 1200);
WIRE 17 273 (-9050 1675)(-6875 1675);
WIRE 17 273 (-9050 525)(-6875 525);
WIRE 17 273 (-9050 1125)(-9050 525);
WIRE 17 273 (-6875 1125)(-6875 525);
WIRE 17 273 (-9050 1125)(-6875 1125);
WIRE 16 -1 (-4025 3450)(-4025 3400);
WIRE 16 -1 (-4025 3400)(-3550 3400);
WIRE 16 -1 (-5225 3400)(-4025 3400);
FORCEPROP 2 LAST SIG_NAME SW_P1V8_RETIMER_CPU0_SW
J 0
(-5120 3417);
DISPLAY 0.489362 (-5120 3417);
FORCEPROP 2 LASTPROP $XRERR UNIQUE?
J 0
(-5360 3417);
DISPLAY 0.638298 (-5360 3417);
PAINT MONO (-5360 3417);
DISPLAY INVISIBLE (-5360 3417);
WIRE 16 -1 (-5225 3900)(-4575 3900);
WIRE 16 -1 (-4575 3900)(-3625 3900);
FORCEPROP 2 LAST SIG_NAME PWRGD_P1V8_RETIMER_CPU0
J 0
(-4360 3925);
DISPLAY 0.489362 (-4360 3925);
FORCEPROP 2 LASTPROP $XRERR UNIQUE?
J 0
(-4600 3925);
DISPLAY 0.638298 (-4600 3925);
PAINT MONO (-4600 3925);
DISPLAY INVISIBLE (-4600 3925);
WIRE 16 -1 (-4575 4100)(-4575 3900);
WIRE 16 -1 (-8450 3875)(-8450 3725);
WIRE 16 -1 (-8450 3725)(-8300 3725);
WIRE 16 -1 (-7975 3725)(-8300 3725);
WIRE 16 -1 (-8300 3875)(-8300 3725);
WIRE 16 -1 (-7750 3725)(-7975 3725);
WIRE 16 -1 (-7975 3875)(-7975 3725);
WIRE 16 -1 (-7550 3725)(-7750 3725);
WIRE 16 -1 (-7750 3875)(-7750 3725);
WIRE 16 -1 (-7550 3875)(-7550 3725);
WIRE 16 -1 (-7475 3725)(-7550 3725);
WIRE 16 -1 (-7350 3725)(-7475 3725);
WIRE 16 -1 (-7475 3675)(-7475 3725);
WIRE 16 -1 (-7350 3725)(-7150 3725);
WIRE 16 -1 (-7350 3875)(-7350 3725);
WIRE 16 -1 (-7150 3725)(-6850 3725);
WIRE 16 -1 (-7150 3875)(-7150 3725);
WIRE 16 -1 (-6850 3725)(-6650 3725);
WIRE 16 -1 (-6850 3875)(-6850 3725);
WIRE 16 -1 (-6650 3875)(-6650 3725);
WIRE 16 -1 (-6650 3725)(-6450 3725);
WIRE 16 -1 (-6450 3875)(-6450 3725);
WIRE 16 -1 (-5000 2550)(-5000 2600);
WIRE 16 -1 (-5000 2325)(-5000 2550);
WIRE 16 -1 (-5225 2550)(-5000 2550);
WIRE 16 -1 (-5000 2600)(-5225 2600);
WIRE 16 -1 (-2800 3050)(-2800 2900);
WIRE 16 -1 (-2425 2900)(-2800 2900);
WIRE 16 -1 (-2150 2900)(-2425 2900);
WIRE 16 -1 (-2425 3050)(-2425 2900);
WIRE 16 -1 (-2150 2900)(-1875 2900);
WIRE 16 -1 (-2150 3050)(-2150 2900);
WIRE 16 -1 (-1875 2900)(-1575 2900);
WIRE 16 -1 (-1875 3050)(-1875 2900);
WIRE 16 -1 (-1300 2900)(-1575 2900);
WIRE 16 -1 (-1575 3050)(-1575 2900);
WIRE 16 -1 (-1000 2900)(-1300 2900);
WIRE 16 -1 (-1300 2900)(-1300 3050);
WIRE 16 -1 (-1000 3050)(-1000 2900);
WIRE 16 -1 (-975 2900)(-1000 2900);
WIRE 16 -1 (-675 2900)(-975 2900);
WIRE 16 -1 (-975 2825)(-975 2900);
WIRE 16 -1 (-675 2900)(-675 3050);
WIRE 16 -1 (-3125 2950)(-2925 2950);
WIRE 16 -1 (-3125 2950)(-3125 2625);
WIRE 16 -1 (-3350 2950)(-3125 2950);
WIRE 16 -1 (-2925 2950)(-2925 2650);
WIRE 16 -1 (-2925 2650)(-375 2650);
WIRE 16 -1 (-3125 2625)(-3350 2625);
WIRE 16 -1 (-375 2650)(-375 3400);
WIRE 16 -1 (-375 3400)(-675 3400);
WIRE 16 -1 (-375 3400)(-375 3725);
WIRE 16 -1 (-675 3250)(-675 3400);
WIRE 16 -1 (-1000 3400)(-675 3400);
WIRE 16 -1 (-1000 3250)(-1000 3400);
WIRE 16 -1 (-1300 3400)(-1000 3400);
WIRE 16 -1 (-1300 3400)(-1300 3250);
WIRE 16 -1 (-1300 3400)(-1575 3400);
WIRE 16 -1 (-1575 3400)(-1575 3250);
WIRE 16 -1 (-1875 3400)(-1575 3400);
WIRE 16 -1 (-1875 3400)(-1875 3250);
WIRE 16 -1 (-2150 3400)(-1875 3400);
WIRE 16 -1 (-2150 3250)(-2150 3400);
WIRE 16 -1 (-2150 3400)(-2425 3400);
WIRE 16 -1 (-2425 3250)(-2425 3400);
WIRE 16 -1 (-2800 3400)(-2425 3400);
WIRE 16 -1 (-2800 3250)(-2800 3400);
WIRE 16 -1 (-3350 3400)(-2800 3400);
WIRE 16 -1 (-8850 4175)(-9100 4175);
WIRE 16 -1 (-9100 4325)(-9100 4175);
WIRE 16 -1 (-9100 4175)(-9100 4075);
WIRE 17 273 (-1800 6325)(-225 6325);
WIRE 17 273 (-1800 6325)(-1800 5475);
WIRE 17 273 (-225 6325)(-225 5475);
WIRE 17 273 (-1800 5475)(-225 5475);
WIRE 16 -1 (-8450 3400)(-6025 3400);
FORCEPROP 2 LAST SIG_NAME P1V8_RETIMER_CPU0_EN
J 0
(-8110 3435);
DISPLAY 0.489362 (-8110 3435);
WIRE 16 -1 (-8450 3400)(-8675 3400);
WIRE 16 -1 (-8450 3400)(-8450 3300);
WIRE 16 -1 (-2525 3900)(-2725 3900);
WIRE 16 -1 (-2725 3850)(-2725 3900);
WIRE 16 -1 (-2725 3900)(-3425 3900);
FORCEPROP 2 LAST SIG_NAME FM_PWRGD_P1V8_RETIMER_CPU0
J 0
(-3210 3925);
DISPLAY 0.489362 (-3210 3925);
WIRE 16 -1 (-3550 2625)(-3750 2625);
WIRE 16 -1 (-3750 2950)(-3750 2625);
WIRE 16 -1 (-3550 2950)(-3750 2950);
WIRE 16 -1 (-3750 2950)(-4025 2950);
WIRE 16 -1 (-4025 2525)(-4025 2950);
WIRE 16 -1 (-5225 2950)(-4025 2950);
FORCEPROP 2 LAST SIG_NAME P1V8_RETIMER_CPU0_FB
J 0
(-5126 2964);
DISPLAY 0.489362 (-5126 2964);
FORCEPROP 2 LASTPROP $XRERR UNIQUE?
J 0
(-5366 2964);
DISPLAY 0.638298 (-5366 2964);
PAINT MONO (-5366 2964);
DISPLAY INVISIBLE (-5366 2964);
WIRE 16 -1 (-5225 3700)(-4550 3700);
FORCEPROP 2 LAST SIG_NAME SW_P1V8_RETIMER_CPU0_BST
J 0
(-5135 3710);
DISPLAY 0.489362 (-5135 3710);
FORCEPROP 2 LASTPROP $XRERR UNIQUE?
J 0
(-5375 3710);
DISPLAY 0.638298 (-5375 3710);
PAINT MONO (-5375 3710);
DISPLAY INVISIBLE (-5375 3710);
WIRE 16 -1 (-8225 3728)(-8225 3722);
WIRE 16 -1 (-6850 3200)(-6025 3200);
FORCEPROP 2 LAST SIG_NAME P1V8_RETIMER_CPU0_MODE
J 0
(-6685 3210);
DISPLAY 0.489362 (-6685 3210);
FORCEPROP 2 LASTPROP $XRERR UNIQUE?
J 0
(-6925 3210);
DISPLAY 0.638298 (-6925 3210);
PAINT MONO (-6925 3210);
DISPLAY INVISIBLE (-6925 3210);
WIRE 16 -1 (-4875 2625)(-4875 2700);
WIRE 16 -1 (-4875 2700)(-5225 2700);
FORCEPROP 2 LAST SIG_NAME P1V8_RETIMER_CPU0_REF
J 0
(-5135 2710);
DISPLAY 0.489362 (-5135 2710);
FORCEPROP 2 LASTPROP $XRERR UNIQUE?
J 0
(-5375 2710);
DISPLAY 0.638298 (-5375 2710);
PAINT MONO (-5375 2710);
DISPLAY INVISIBLE (-5375 2710);
WIRE 16 -1 (-3482 2047)(-3482 2048);
WIRE 16 -1 (-4025 3650)(-4025 3700);
WIRE 16 -1 (-4350 3700)(-4025 3700);
FORCEPROP 2 LAST SIG_NAME SW_P1V8_RETIMER_CPU0_BST_R
J 0
(-4385 3710);
DISPLAY 0.297872 (-4385 3710);
FORCEPROP 2 LASTPROP $XRERR UNIQUE?
J 0
(-4625 3710);
DISPLAY 0.638298 (-4625 3710);
PAINT MONO (-4625 3710);
DISPLAY INVISIBLE (-4625 3710);
WIRE 16 -1 (-6575 2600)(-6025 2600);
WIRE 16 -1 (-6575 2475)(-6575 2600);
FORCEPROP 2 LAST SIG_NAME P1V8_RETIMER_CPU0_CS
J 0
(-6610 2625);
DISPLAY 0.489362 (-6610 2625);
FORCEPROP 2 LASTPROP $XRERR UNIQUE?
J 0
(-6850 2625);
DISPLAY 0.638298 (-6850 2625);
PAINT MONO (-6850 2625);
DISPLAY INVISIBLE (-6850 2625);
WIRE 16 -1 (-7450 2475)(-7450 2600);
WIRE 16 -1 (-7450 2600)(-6900 2600);
WIRE 16 -1 (-7450 2700)(-7450 2600);
WIRE 16 -1 (-6900 2600)(-6900 2950);
WIRE 16 -1 (-6025 2950)(-6900 2950);
FORCEPROP 2 LAST SIG_NAME P1V8_RETIMER_CPU0_VCC
J 0
(-6685 2975);
DISPLAY 0.489362 (-6685 2975);
FORCEPROP 2 LASTPROP $XRERR UNIQUE?
J 0
(-6925 2975);
DISPLAY 0.638298 (-6925 2975);
PAINT MONO (-6925 2975);
DISPLAY INVISIBLE (-6925 2975);
WIRE 16 -1 (-6200 3850)(-6025 3850);
WIRE 16 -1 (-6200 3900)(-6200 3850);
WIRE 16 -1 (-6200 4175)(-6200 3900);
WIRE 16 -1 (-6200 3900)(-6025 3900);
WIRE 16 -1 (-6200 4175)(-6450 4175);
WIRE 16 -1 (-6650 4175)(-6450 4175);
WIRE 16 -1 (-6450 4175)(-6450 4075);
WIRE 16 -1 (-6650 4175)(-6850 4175);
WIRE 16 -1 (-6650 4075)(-6650 4175);
WIRE 16 -1 (-6850 4175)(-7150 4175);
WIRE 16 -1 (-6850 4075)(-6850 4175);
WIRE 16 -1 (-7150 4175)(-7350 4175);
WIRE 16 -1 (-7150 4075)(-7150 4175);
WIRE 16 -1 (-7350 4175)(-7550 4175);
WIRE 16 -1 (-7350 4075)(-7350 4175);
WIRE 16 -1 (-7550 4175)(-7750 4175);
FORCEPROP 2 LAST SIG_NAME SW_P12V_AUX_P1V8_RETIMER_CPU0_FLT
J 0
(-7637 4198);
DISPLAY 0.489362 (-7637 4198);
FORCEPROP 2 LASTPROP $XRERR UNIQUE?
J 0
(-7877 4198);
DISPLAY 0.638298 (-7877 4198);
PAINT MONO (-7877 4198);
DISPLAY INVISIBLE (-7877 4198);
WIRE 16 -1 (-7550 4075)(-7550 4175);
WIRE 16 -1 (-7750 4175)(-7975 4175);
WIRE 16 -1 (-7750 4075)(-7750 4175);
WIRE 16 -1 (-7975 4075)(-7975 4175);
WIRE 16 -1 (-7975 4175)(-8300 4175);
WIRE 16 -1 (-8450 4175)(-8300 4175);
WIRE 16 -1 (-8300 4075)(-8300 4175);
WIRE 16 -1 (-8650 4175)(-8450 4175);
WIRE 16 -1 (-8450 4075)(-8450 4175);
DOT 1 (-1000 3400);
DOT 1 (-1300 3400);
DOT 1 (-375 3400);
DOT 1 (-3750 2950);
DOT 1 (-3125 2950);
DOT 1 (-2800 3400);
DOT 1 (-8450 3400);
DOT 1 (-9100 4175);
DOT 1 (-7450 2600);
DOT 1 (-6200 3900);
DOT 1 (-5000 2550);
DOT 1 (-4575 3900);
DOT 1 (-4025 2950);
DOT 1 (-4025 3400);
DOT 1 (-2725 3900);
DOT 1 (-2150 3400);
DOT 1 (-1300 2900);
DOT 1 (-1000 2900);
DOT 1 (-2425 3400);
DOT 1 (-2150 2900);
DOT 1 (-1575 3400);
DOT 1 (-1575 2900);
DOT 1 (-2425 2900);
DOT 1 (-1875 3400);
DOT 1 (-975 2900);
DOT 1 (-1875 2900);
DOT 1 (-675 3400);
DOT 1 (-8450 4175);
DOT 1 (-8300 4175);
DOT 1 (-8300 3725);
DOT 1 (-7750 4175);
DOT 1 (-7550 4175);
DOT 1 (-7150 3725);
DOT 1 (-7350 3725);
DOT 1 (-7350 4175);
DOT 1 (-7475 3725);
DOT 1 (-7550 3725);
DOT 1 (-7750 3725);
DOT 1 (-7975 3725);
DOT 1 (-7975 4175);
DOT 1 (-6450 4175);
DOT 1 (-6650 3725);
DOT 1 (-6850 4175);
DOT 1 (-6850 3725);
DOT 1 (-6650 4175);
DOT 1 (-7150 4175);
FORCENOTE
ISAT:47A@100C
(-3650 3275) 0;
DISPLAY LEFT (-3650 3275);
DISPLAY 0.638298 (-3650 3275);
PAINT WHITE (-3650 3275);
FORCENOTE
2ND=CV-10^0MZ03
(-3650 3125) 0;
DISPLAY LEFT (-3650 3125);
DISPLAY 0.638298 (-3650 3125);
PAINT WHITE (-3650 3125);
FORCENOTE
P1V8_CPU0_RT_1D
(-6875 5400) 0;
DISPLAY LEFT (-6875 5400);
DISPLAY 3.148936 (-6875 5400);
PAINT WHITE (-6875 5400);
FORCENOTE
DCR=2.5M OHM
(-3650 3175) 0;
DISPLAY LEFT (-3650 3175);
DISPLAY 0.638298 (-3650 3175);
PAINT WHITE (-3650 3175);
FORCENOTE
RA
(-3500 3050) 0;
DISPLAY LEFT (-3500 3050);
DISPLAY 1.021277 (-3500 3050);
PAINT WHITE (-3500 3050);
FORCENOTE
VOUT=0.6(1+RA/RB)=1.8V
(-4200 1900) 0;
DISPLAY LEFT (-4200 1900);
DISPLAY 2.000000 (-4200 1900);
PAINT WHITE (-4200 1900);
FORCENOTE
FCCM
(-8600 2775) 0;
DISPLAY LEFT (-8600 2775);
DISPLAY 1.276596 (-8600 2775);
PAINT WHITE (-8600 2775);
FORCENOTE
4.5*4.7*4.5
(-8550 4400) 0;
DISPLAY LEFT (-8550 4400);
DISPLAY 0.638298 (-8550 4400);
PAINT WHITE (-8550 4400);
FORCENOTE
2ND=CV+10G0MZ12
(-8550 4300) 0;
DISPLAY LEFT (-8550 4300);
DISPLAY 0.638298 (-8550 4300);
PAINT WHITE (-8550 4300);
FORCENOTE
DCR:0.105M OHM
(-8550 4350) 0;
DISPLAY LEFT (-8550 4350);
DISPLAY 0.638298 (-8550 4350);
PAINT WHITE (-8550 4350);
FORCENOTE
FSW=600KHZ
(-8600 2675) 0;
DISPLAY LEFT (-8600 2675);
DISPLAY 1.276596 (-8600 2675);
PAINT WHITE (-8600 2675);
FORCENOTE
SPECFICATION
(-1775 6250) 0;
DISPLAY LEFT (-1775 6250);
DISPLAY 1.276596 (-1775 6250);
PAINT WHITE (-1775 6250);
FORCENOTE
13*13*5.0
(-3650 3225) 0;
DISPLAY LEFT (-3650 3225);
DISPLAY 0.638298 (-3650 3225);
PAINT WHITE (-3650 3225);
FORCENOTE
PCMC135T-1R0MF
(-3650 3325) 0;
DISPLAY LEFT (-3650 3325);
DISPLAY 0.638298 (-3650 3325);
PAINT WHITE (-3650 3325);
FORCENOTE
RB
(-4150 2400) 0;
DISPLAY LEFT (-4150 2400);
DISPLAY 1.021277 (-4150 2400);
PAINT WHITE (-4150 2400);
FORCENOTE
5.0*5.8
(-1425 2800) 0;
DISPLAY LEFT (-1425 2800);
DISPLAY 0.510638 (-1425 2800);
FORCENOTE
ESR=10M OHM
(-1425 2850) 0;
DISPLAY LEFT (-1425 2850);
DISPLAY 0.510638 (-1425 2850);
FORCENOTE
2ND=CC7390JMZ11
(-1425 2750) 0;
DISPLAY LEFT (-1425 2750);
DISPLAY 0.510638 (-1425 2750);
PAINT WHITE (-1425 2750);
FORCENOTE
ISAT:13A@100C
(-8550 4450) 0;
DISPLAY LEFT (-8550 4450);
DISPLAY 0.638298 (-8550 4450);
PAINT WHITE (-8550 4450);
FORCENOTE
PG2289.101HLT
(-8550 4500) 0;
DISPLAY LEFT (-8550 4500);
DISPLAY 0.638298 (-8550 4500);
PAINT WHITE (-8550 4500);
FORCENOTE
3RD=CV+10G0MZ08
(-8550 4250) 0;
DISPLAY LEFT (-8550 4250);
DISPLAY 0.638298 (-8550 4250);
PAINT WHITE (-8550 4250);
FORCENOTE
EFFICIENCY > 90% @TDC
(-1775 5525) 0;
DISPLAY LEFT (-1775 5525);
DISPLAY 0.936170 (-1775 5525);
PAINT WHITE (-1775 5525);
FORCENOTE
IOUT TDC=14.6A
(-1775 5975) 0;
DISPLAY LEFT (-1775 5975);
DISPLAY 0.936170 (-1775 5975);
PAINT WHITE (-1775 5975);
FORCENOTE
OUTPUT VOLTAGE=1.8V +/- 5%
(-1775 6125) 0;
DISPLAY LEFT (-1775 6125);
DISPLAY 0.936170 (-1775 6125);
PAINT WHITE (-1775 6125);
FORCENOTE
AC + DC =1.710-1.890
(-1775 6050) 0;
DISPLAY LEFT (-1775 6050);
DISPLAY 0.936170 (-1775 6050);
PAINT WHITE (-1775 6050);
FORCENOTE
IOUT MAX=15.72A
(-1775 5900) 0;
DISPLAY LEFT (-1775 5900);
DISPLAY 0.936170 (-1775 5900);
PAINT WHITE (-1775 5900);
FORCENOTE
OCP=17.52A (IOUT MAX*1.2)
(-1775 5825) 0;
DISPLAY LEFT (-1775 5825);
DISPLAY 0.936170 (-1775 5825);
PAINT WHITE (-1775 5825);
FORCENOTE
LOAD STEP=7.2A
(-1775 5750) 0;
DISPLAY LEFT (-1775 5750);
DISPLAY 0.936170 (-1775 5750);
PAINT WHITE (-1775 5750);
FORCENOTE
SLEW RATE=1A/US
(-1775 5675) 0;
DISPLAY LEFT (-1775 5675);
DISPLAY 0.936170 (-1775 5675);
PAINT WHITE (-1775 5675);
FORCENOTE
WORK FREQUENCY=600KHZ
(-1775 5600) 0;
DISPLAY LEFT (-1775 5600);
DISPLAY 0.936170 (-1775 5600);
PAINT WHITE (-1775 5600);
FORCENOTE
BOM CHANGE R&C TABLE
(-8975 1025) 0;
DISPLAY LEFT (-8975 1025);
DISPLAY 1.276596 (-8975 1025);
PAINT WHITE (-8975 1025);
FORCENOTE
1ST AL008633005 / MPQ8633BGLE-C838-Z/ MPS
(-8975 1475) 0;
DISPLAY LEFT (-8975 1475);
DISPLAY 1.021277 (-8975 1475);
FORCENOTE
BOM NOTE
(-8975 1575) 0;
DISPLAY LEFT (-8975 1575);
DISPLAY 1.276596 (-8975 1575);
PAINT WHITE (-8975 1575);
FORCENOTE
2ND AL053319002 / RS53319LR / REEDSEMI
(-8975 1400) 0;
DISPLAY LEFT (-8975 1400);
DISPLAY 1.021277 (-8975 1400);
QUIT
